FILE_TYPE = MACRO_DRAWING;
SET COLOR_WIRE YELLOW;
SET COLOR_PROP ORANGE;
SET COLOR_DOT WHITE;
SET COLOR_ARC YELLOW;
SET COLOR_BODY GREEN;
SET COLOR_NOTE PURPLE;
SET PROP_DISPLAY VALUE;
SET PAGE_NUMBER P392;
FORCEADD UNIVERSAL_GND..1
(-3475 4750);
FORCEPROP 3 LASTPIN (-3475 4800) SIG_NAME GND\g
J 0
(-3465 4810);
DISPLAY 0.659574 (-3465 4810);
PAINT MONO (-3465 4810);
DISPLAY INVISIBLE (-3465 4810);
FORCEPROP 2 LAST CDS_LIB pure_quanta_power
J 0
(-3475 4750);
DISPLAY INVISIBLE (-3475 4750);
FORCEPROP 1 LAST HDL_POWER GND
J 1
(-3450 4675);
DISPLAY 0.872340 (-3450 4675);
PAINT GREEN (-3450 4675);
DISPLAY INVISIBLE (-3450 4675);
FORCEPROP 1 LAST PATH I100
J 0
(-3400 4750);
DISPLAY 0.872340 (-3400 4750);
PAINT AQUA (-3400 4750);
DISPLAY INVISIBLE (-3400 4750);
FORCEADD Q_RES..2
(-3475 5175);
FORCEPROP 1 LAST LOCATION R741
J 0
(-3430 5300);
DISPLAY 0.787234 (-3430 5300);
FORCEPROP 0 LAST $SEC 1
J 0
(-3425 5350);
DISPLAY 0.680851 (-3425 5350);
PAINT MONO (-3425 5350);
DISPLAY INVISIBLE (-3425 5350);
FORCEPROP 0 LAST CDS_SEC 1
J 0
(-3425 5350);
DISPLAY 0.680851 (-3425 5350);
DISPLAY INVISIBLE (-3425 5350);
FORCEPROP 1 LASTPIN (-3475 5275) $PN 1
J 0
(-3470 5237);
DISPLAY 0.787234 (-3470 5237);
PAINT MONO (-3470 5237);
FORCEPROP 1 LASTPIN (-3475 5075) $PN 2
J 0
(-3470 5085);
DISPLAY 0.787234 (-3470 5085);
PAINT MONO (-3470 5085);
FORCEPROP 1 LAST TOLERANCE 1%
J 0
(-3430 5200);
DISPLAY 0.787234 (-3430 5200);
FORCEPROP 1 LAST VALUE 1K
J 0
(-3430 5250);
DISPLAY 0.787234 (-3430 5250);
FORCEPROP 1 LAST WATTAGE 1/20W
J 0
(-3435 5150);
DISPLAY 0.787234 (-3435 5150);
FORCEPROP 1 LAST MATERIAL EMPTY
J 0
(-3435 5100);
DISPLAY 0.787234 (-3435 5100);
FORCEPROP 1 LAST PACK_TYPE 0201LF
J 0
(-3435 5000);
DISPLAY 0.787234 (-3435 5000);
FORCEPROP 2 LAST CDS_LIB pure_quanta
J 0
(-3475 5175);
DISPLAY INVISIBLE (-3475 5175);
FORCEPROP 1 LAST PATH I101
J 0
(-3425 5350);
DISPLAY 0.978723 (-3425 5350);
PAINT WHITE (-3425 5350);
DISPLAY INVISIBLE (-3425 5350);
FORCEPROP 1 LAST PART_NUMBER CS21001FE07
J 0
(-3435 5050);
DISPLAY 0.978723 (-3435 5050);
DISPLAY INVISIBLE (-3435 5050);
FORCEADD Q_RES..2
(-3175 5175);
FORCEPROP 1 LAST LOCATION R746
J 0
(-3130 5300);
DISPLAY 0.787234 (-3130 5300);
FORCEPROP 0 LAST $SEC 1
J 0
(-3125 5350);
DISPLAY 0.680851 (-3125 5350);
PAINT MONO (-3125 5350);
DISPLAY INVISIBLE (-3125 5350);
FORCEPROP 0 LAST CDS_SEC 1
J 0
(-3125 5350);
DISPLAY 0.680851 (-3125 5350);
DISPLAY INVISIBLE (-3125 5350);
FORCEPROP 1 LASTPIN (-3175 5275) $PN 1
J 0
(-3170 5237);
DISPLAY 0.787234 (-3170 5237);
PAINT MONO (-3170 5237);
FORCEPROP 1 LASTPIN (-3175 5075) $PN 2
J 0
(-3170 5085);
DISPLAY 0.787234 (-3170 5085);
PAINT MONO (-3170 5085);
FORCEPROP 1 LAST TOLERANCE 1%
J 0
(-3130 5200);
DISPLAY 0.787234 (-3130 5200);
FORCEPROP 1 LAST VALUE 20K
J 0
(-3130 5250);
DISPLAY 0.787234 (-3130 5250);
FORCEPROP 1 LAST PACK_TYPE 0201LF
J 0
(-3135 5000);
DISPLAY 0.787234 (-3135 5000);
FORCEPROP 1 LAST MATERIAL CHIP
J 0
(-3135 5100);
DISPLAY 0.787234 (-3135 5100);
FORCEPROP 1 LAST WATTAGE 1/20W
J 0
(-3135 5150);
DISPLAY 0.787234 (-3135 5150);
FORCEPROP 2 LAST CDS_LIB pure_quanta
J 0
(-3175 5175);
DISPLAY INVISIBLE (-3175 5175);
FORCEPROP 1 LAST PATH I102
J 0
(-3125 5350);
DISPLAY 0.978723 (-3125 5350);
PAINT WHITE (-3125 5350);
DISPLAY INVISIBLE (-3125 5350);
FORCEPROP 1 LAST PART_NUMBER CS32001FE00
J 0
(-3135 5050);
DISPLAY 0.978723 (-3135 5050);
DISPLAY INVISIBLE (-3135 5050);
FORCEADD Q_RES..2
(-3475 5950);
FORCEPROP 1 LAST LOCATION R735
J 0
(-3430 6075);
DISPLAY 0.787234 (-3430 6075);
FORCEPROP 0 LAST $SEC 1
J 0
(-3425 6125);
DISPLAY 0.680851 (-3425 6125);
PAINT MONO (-3425 6125);
DISPLAY INVISIBLE (-3425 6125);
FORCEPROP 0 LAST CDS_SEC 1
J 0
(-3425 6125);
DISPLAY 0.680851 (-3425 6125);
DISPLAY INVISIBLE (-3425 6125);
FORCEPROP 1 LASTPIN (-3475 6050) $PN 1
J 0
(-3470 6012);
DISPLAY 0.787234 (-3470 6012);
PAINT MONO (-3470 6012);
FORCEPROP 1 LASTPIN (-3475 5850) $PN 2
J 0
(-3470 5860);
DISPLAY 0.787234 (-3470 5860);
PAINT MONO (-3470 5860);
FORCEPROP 1 LAST PACK_TYPE 0201LF
J 0
(-3435 5775);
DISPLAY 0.787234 (-3435 5775);
FORCEPROP 1 LAST MATERIAL CHIP
J 0
(-3435 5875);
DISPLAY 0.787234 (-3435 5875);
FORCEPROP 1 LAST VALUE 1K
J 0
(-3430 6025);
DISPLAY 0.787234 (-3430 6025);
FORCEPROP 1 LAST TOLERANCE 1%
J 0
(-3430 5975);
DISPLAY 0.787234 (-3430 5975);
FORCEPROP 1 LAST WATTAGE 1/20W
J 0
(-3435 5925);
DISPLAY 0.787234 (-3435 5925);
FORCEPROP 2 LAST CDS_LIB pure_quanta
J 0
(-3475 5950);
DISPLAY INVISIBLE (-3475 5950);
FORCEPROP 1 LAST PATH I103
J 0
(-3425 6125);
DISPLAY 0.978723 (-3425 6125);
PAINT WHITE (-3425 6125);
DISPLAY INVISIBLE (-3425 6125);
FORCEPROP 1 LAST PART_NUMBER CS21001FE07
J 0
(-3435 5825);
DISPLAY 0.978723 (-3435 5825);
DISPLAY INVISIBLE (-3435 5825);
FORCEADD Q_RES..2
(-3175 5950);
FORCEPROP 1 LAST LOCATION R745
J 0
(-3130 6075);
DISPLAY 0.978723 (-3130 6075);
FORCEPROP 0 LAST $SEC 1
J 0
(-3125 6125);
DISPLAY 0.680851 (-3125 6125);
PAINT MONO (-3125 6125);
DISPLAY INVISIBLE (-3125 6125);
FORCEPROP 0 LAST CDS_SEC 1
J 0
(-3125 6125);
DISPLAY 0.680851 (-3125 6125);
DISPLAY INVISIBLE (-3125 6125);
FORCEPROP 1 LASTPIN (-3175 6050) $PN 1
J 0
(-3170 6012);
DISPLAY 0.787234 (-3170 6012);
PAINT MONO (-3170 6012);
FORCEPROP 1 LASTPIN (-3175 5850) $PN 2
J 0
(-3170 5860);
DISPLAY 0.787234 (-3170 5860);
PAINT MONO (-3170 5860);
FORCEPROP 1 LAST TOLERANCE 1%
J 0
(-3130 5975);
DISPLAY 0.787234 (-3130 5975);
FORCEPROP 1 LAST VALUE 1K
J 0
(-3130 6025);
DISPLAY 0.787234 (-3130 6025);
FORCEPROP 1 LAST WATTAGE 1/20W
J 0
(-3135 5925);
DISPLAY 0.787234 (-3135 5925);
FORCEPROP 1 LAST PACK_TYPE 0201LF
J 0
(-3135 5775);
DISPLAY 0.787234 (-3135 5775);
FORCEPROP 1 LAST MATERIAL EMPTY
J 0
(-3135 5875);
DISPLAY 0.787234 (-3135 5875);
FORCEPROP 2 LAST CDS_LIB pure_quanta
J 0
(-3175 5950);
DISPLAY INVISIBLE (-3175 5950);
FORCEPROP 1 LAST PATH I104
J 0
(-3125 6125);
DISPLAY 0.978723 (-3125 6125);
PAINT WHITE (-3125 6125);
DISPLAY INVISIBLE (-3125 6125);
FORCEPROP 1 LAST PART_NUMBER CS21001FE07
J 0
(-3135 5825);
DISPLAY 0.978723 (-3135 5825);
DISPLAY INVISIBLE (-3135 5825);
FORCEADD Q_RES..2
(-2825 5175);
FORCEPROP 1 LAST LOCATION R796
J 0
(-2780 5300);
DISPLAY 0.978723 (-2780 5300);
FORCEPROP 0 LAST $SEC 1
J 0
(-2775 5350);
DISPLAY 0.680851 (-2775 5350);
PAINT MONO (-2775 5350);
DISPLAY INVISIBLE (-2775 5350);
FORCEPROP 0 LAST CDS_SEC 1
J 0
(-2775 5350);
DISPLAY 0.680851 (-2775 5350);
DISPLAY INVISIBLE (-2775 5350);
FORCEPROP 1 LASTPIN (-2825 5275) $PN 1
J 0
(-2820 5237);
DISPLAY 0.787234 (-2820 5237);
PAINT MONO (-2820 5237);
FORCEPROP 1 LASTPIN (-2825 5075) $PN 2
J 0
(-2820 5085);
DISPLAY 0.787234 (-2820 5085);
PAINT MONO (-2820 5085);
FORCEPROP 1 LAST PACK_TYPE 0201LF
J 0
(-2785 5000);
DISPLAY 0.787234 (-2785 5000);
FORCEPROP 1 LAST WATTAGE 1/20W
J 0
(-2785 5150);
DISPLAY 0.787234 (-2785 5150);
FORCEPROP 1 LAST MATERIAL CHIP
J 0
(-2785 5100);
DISPLAY 0.787234 (-2785 5100);
FORCEPROP 1 LAST VALUE 1K
J 0
(-2780 5250);
DISPLAY 0.787234 (-2780 5250);
FORCEPROP 1 LAST TOLERANCE 1%
J 0
(-2780 5200);
DISPLAY 0.787234 (-2780 5200);
FORCEPROP 2 LAST CDS_LIB pure_quanta
J 0
(-2825 5175);
DISPLAY INVISIBLE (-2825 5175);
FORCEPROP 1 LAST PATH I105
J 0
(-2775 5350);
DISPLAY 0.978723 (-2775 5350);
PAINT WHITE (-2775 5350);
DISPLAY INVISIBLE (-2775 5350);
FORCEPROP 1 LAST PART_NUMBER CS21001FE07
J 0
(-2785 5050);
DISPLAY 0.978723 (-2785 5050);
DISPLAY INVISIBLE (-2785 5050);
FORCEADD P1V0..1
(-3475 6375);
FORCEPROP 3 LASTPIN (-3475 6325) SIG_NAME P1V8_CPU1_RT_1D\g
J 0
(-3465 6335);
DISPLAY 0.659574 (-3465 6335);
PAINT MONO (-3465 6335);
DISPLAY INVISIBLE (-3465 6335);
FORCEPROP 1 LAST HDL_POWER P1V8_CPU1_RT_1D
J 1
(-3475 6425);
DISPLAY 0.489362 (-3475 6425);
PAINT SKYBLUE (-3475 6425);
FORCEPROP 2 LAST CDS_LIB pure_quanta_power
J 0
(-3475 6375);
DISPLAY INVISIBLE (-3475 6375);
FORCEPROP 1 LAST PATH I106
J 0
(-3425 6400);
DISPLAY 0.872340 (-3425 6400);
PAINT AQUA (-3425 6400);
DISPLAY INVISIBLE (-3425 6400);
FORCEADD OFFPAGE..5
R 2
(-1925 5425);
FORCEPROP 2 LAST $XR0 332 
J 0
(-1736 5425);
DISPLAY 0.638298 (-1736 5425);
PAINT MONO (-1736 5425);
FORCEPROP 2 LAST CDS_LIB standard
J 0
(-1925 5425);
DISPLAY INVISIBLE (-1925 5425);
FORCEPROP 1 LAST OFFPAGE TRUE
J 2
(-2250 5300);
DISPLAY 0.872340 (-2250 5300);
PAINT GREEN (-2250 5300);
DISPLAY INVISIBLE (-2250 5300);
FORCEPROP 1 LAST COMMENT_BODY TRUE
J 2
(-2025 5350);
DISPLAY 0.872340 (-2025 5350);
PAINT GREEN (-2025 5350);
DISPLAY INVISIBLE (-2025 5350);
FORCEPROP 2 LAST PATH I107
J 0
(-1725 5475);
DISPLAY 0.680851 (-1725 5475);
DISPLAY INVISIBLE (-1725 5475);
FORCEADD OFFPAGE..5
R 2
(-1925 5525);
FORCEPROP 2 LAST $XR0 332 
J 0
(-1736 5525);
DISPLAY 0.638298 (-1736 5525);
PAINT MONO (-1736 5525);
FORCEPROP 2 LAST CDS_LIB standard
J 0
(-1925 5525);
DISPLAY INVISIBLE (-1925 5525);
FORCEPROP 1 LAST OFFPAGE TRUE
J 2
(-2250 5400);
DISPLAY 0.872340 (-2250 5400);
PAINT GREEN (-2250 5400);
DISPLAY INVISIBLE (-2250 5400);
FORCEPROP 1 LAST COMMENT_BODY TRUE
J 2
(-2025 5450);
DISPLAY 0.872340 (-2025 5450);
PAINT GREEN (-2025 5450);
DISPLAY INVISIBLE (-2025 5450);
FORCEPROP 2 LAST PATH I108
J 0
(-1725 5575);
DISPLAY 0.680851 (-1725 5575);
DISPLAY INVISIBLE (-1725 5575);
FORCEADD OFFPAGE..5
R 2
(-1925 5625);
FORCEPROP 2 LAST $XR0 332 
J 0
(-1736 5625);
DISPLAY 0.638298 (-1736 5625);
PAINT MONO (-1736 5625);
FORCEPROP 2 LAST CDS_LIB standard
J 0
(-1925 5625);
DISPLAY INVISIBLE (-1925 5625);
FORCEPROP 1 LAST OFFPAGE TRUE
J 2
(-2250 5500);
DISPLAY 0.872340 (-2250 5500);
PAINT GREEN (-2250 5500);
DISPLAY INVISIBLE (-2250 5500);
FORCEPROP 1 LAST COMMENT_BODY TRUE
J 2
(-2025 5550);
DISPLAY 0.872340 (-2025 5550);
PAINT GREEN (-2025 5550);
DISPLAY INVISIBLE (-2025 5550);
FORCEPROP 2 LAST PATH I109
J 0
(-1725 5675);
DISPLAY 0.680851 (-1725 5675);
DISPLAY INVISIBLE (-1725 5675);
FORCEADD Q_RES..2
(-2825 5925);
FORCEPROP 1 LAST LOCATION R795
J 0
(-2780 6050);
DISPLAY 0.978723 (-2780 6050);
FORCEPROP 0 LAST $SEC 1
J 0
(-2775 6100);
DISPLAY 0.680851 (-2775 6100);
PAINT MONO (-2775 6100);
DISPLAY INVISIBLE (-2775 6100);
FORCEPROP 0 LAST CDS_SEC 1
J 0
(-2775 6100);
DISPLAY 0.680851 (-2775 6100);
DISPLAY INVISIBLE (-2775 6100);
FORCEPROP 1 LASTPIN (-2825 6025) $PN 1
J 0
(-2820 5987);
DISPLAY 0.787234 (-2820 5987);
PAINT MONO (-2820 5987);
FORCEPROP 1 LASTPIN (-2825 5825) $PN 2
J 0
(-2820 5835);
DISPLAY 0.787234 (-2820 5835);
PAINT MONO (-2820 5835);
FORCEPROP 1 LAST MATERIAL EMPTY
J 0
(-2785 5850);
DISPLAY 0.787234 (-2785 5850);
FORCEPROP 1 LAST TOLERANCE 1%
J 0
(-2780 5950);
DISPLAY 0.787234 (-2780 5950);
FORCEPROP 1 LAST VALUE 1K
J 0
(-2780 6000);
DISPLAY 0.787234 (-2780 6000);
FORCEPROP 1 LAST WATTAGE 1/20W
J 0
(-2785 5900);
DISPLAY 0.787234 (-2785 5900);
FORCEPROP 1 LAST PACK_TYPE 0201LF
J 0
(-2785 5750);
DISPLAY 0.787234 (-2785 5750);
FORCEPROP 2 LAST CDS_LIB pure_quanta
J 0
(-2825 5925);
DISPLAY INVISIBLE (-2825 5925);
FORCEPROP 1 LAST PATH I110
J 0
(-2775 6100);
DISPLAY 0.978723 (-2775 6100);
PAINT WHITE (-2775 6100);
DISPLAY INVISIBLE (-2775 6100);
FORCEPROP 1 LAST PART_NUMBER CS21001FE07
J 0
(-2785 5800);
DISPLAY 0.978723 (-2785 5800);
DISPLAY INVISIBLE (-2785 5800);
FORCEADD Q_RES..1
(-2525 2150);
FORCEPROP 1 LAST LOCATION R1376
J 0
(-2575 2200);
DISPLAY 0.978723 (-2575 2200);
FORCEPROP 0 LAST $SEC 1
J 0
(-2575 2250);
DISPLAY 0.680851 (-2575 2250);
PAINT MONO (-2575 2250);
DISPLAY INVISIBLE (-2575 2250);
FORCEPROP 0 LAST CDS_SEC 1
J 0
(-2575 2250);
DISPLAY 0.680851 (-2575 2250);
DISPLAY INVISIBLE (-2575 2250);
FORCEPROP 1 LASTPIN (-2625 2150) $PN 1
J 0
(-2613 2162);
DISPLAY 0.787234 (-2613 2162);
PAINT MONO (-2613 2162);
FORCEPROP 1 LASTPIN (-2425 2150) $PN 2
J 0
(-2463 2162);
DISPLAY 0.787234 (-2463 2162);
PAINT MONO (-2463 2162);
FORCEPROP 1 LAST VALUE 4.7K
J 2
(-2275 2150);
DISPLAY 0.638298 (-2275 2150);
FORCEPROP 1 LAST PACK_TYPE 0201LF
J 0
(-2100 2150);
DISPLAY 0.638298 (-2100 2150);
FORCEPROP 1 LAST MATERIAL CHIP
J 0
(-2250 2150);
DISPLAY 0.638298 (-2250 2150);
FORCEPROP 2 LAST CDS_LIB pure_quanta
J 0
(-2525 2150);
DISPLAY INVISIBLE (-2525 2150);
FORCEPROP 1 LAST TOLERANCE 5%
J 0
(-2525 2050);
DISPLAY 0.978723 (-2525 2050);
DISPLAY INVISIBLE (-2525 2050);
FORCEPROP 1 LAST WATTAGE 1/20W
J 2
(-2550 2000);
DISPLAY 0.978723 (-2550 2000);
DISPLAY INVISIBLE (-2550 2000);
FORCEPROP 1 LAST PATH I111
J 0
(-2575 2300);
DISPLAY 0.978723 (-2575 2300);
PAINT WHITE (-2575 2300);
DISPLAY INVISIBLE (-2575 2300);
FORCEPROP 1 LAST PART_NUMBER CS24701JE04
J 0
(-2575 2250);
DISPLAY 0.978723 (-2575 2250);
DISPLAY INVISIBLE (-2575 2250);
FORCEADD OFFPAGE..1
R 2
(-2250 2550);
FORCEPROP 2 LAST $XR0 332 
J 0
(-2064 2550);
DISPLAY 0.638298 (-2064 2550);
PAINT MONO (-2064 2550);
FORCEPROP 2 LAST CDS_LIB standard
J 0
(-2250 2550);
DISPLAY INVISIBLE (-2250 2550);
FORCEPROP 1 LAST OFFPAGE TRUE
J 2
(-2575 2425);
DISPLAY 0.872340 (-2575 2425);
DISPLAY INVISIBLE (-2575 2425);
FORCEPROP 1 LAST COMMENT_BODY TRUE
J 2
(-2375 2450);
DISPLAY 0.872340 (-2375 2450);
PAINT GREEN (-2375 2450);
DISPLAY INVISIBLE (-2375 2450);
FORCEPROP 2 LAST PATH I112
J 0
(-2075 2625);
DISPLAY 0.680851 (-2075 2625);
DISPLAY INVISIBLE (-2075 2625);
FORCEADD Q_RES..1
(-2550 3100);
FORCEPROP 1 LAST LOCATION R1372
J 0
(-2675 3100);
DISPLAY 0.787234 (-2675 3100);
PAINT WHITE (-2675 3100);
FORCEPROP 0 LAST $SEC 1
J 0
(-2175 3150);
DISPLAY 0.680851 (-2175 3150);
PAINT MONO (-2175 3150);
DISPLAY INVISIBLE (-2175 3150);
FORCEPROP 0 LAST CDS_SEC 1
J 0
(-2175 3150);
DISPLAY 0.680851 (-2175 3150);
DISPLAY INVISIBLE (-2175 3150);
FORCEPROP 1 LASTPIN (-2650 3100) $PN 1
J 0
(-2638 3112);
DISPLAY 0.787234 (-2638 3112);
PAINT MONO (-2638 3112);
FORCEPROP 1 LASTPIN (-2450 3100) $PN 2
J 0
(-2488 3112);
DISPLAY 0.787234 (-2488 3112);
PAINT MONO (-2488 3112);
FORCEPROP 1 LAST PACK_TYPE 0201LF
J 0
(-2175 3100);
DISPLAY 0.638298 (-2175 3100);
FORCEPROP 1 LAST VALUE 1K
J 2
(-2350 3100);
DISPLAY 0.638298 (-2350 3100);
FORCEPROP 1 LAST MATERIAL CHIP
J 0
(-2325 3100);
DISPLAY 0.638298 (-2325 3100);
FORCEPROP 2 LAST CDS_LIB pure_quanta
J 0
(-2550 3100);
DISPLAY INVISIBLE (-2550 3100);
FORCEPROP 1 LAST WATTAGE 1/20W
J 2
(-2575 2950);
DISPLAY 0.638298 (-2575 2950);
DISPLAY INVISIBLE (-2575 2950);
FORCEPROP 1 LAST TOLERANCE 1%
J 0
(-2550 3000);
DISPLAY 0.638298 (-2550 3000);
DISPLAY INVISIBLE (-2550 3000);
FORCEPROP 1 LAST PATH I115
J 0
(-2600 3250);
DISPLAY 0.978723 (-2600 3250);
PAINT WHITE (-2600 3250);
DISPLAY INVISIBLE (-2600 3250);
FORCEPROP 1 LAST PART_NUMBER CS21001FE07
J 0
(-2600 3200);
DISPLAY 0.978723 (-2600 3200);
DISPLAY INVISIBLE (-2600 3200);
FORCEADD UNIVERSAL_GND..1
R 1
(-1800 2150);
FORCEPROP 3 LASTPIN (-1850 2150) SIG_NAME GND\g
J 0
(-1840 2160);
DISPLAY 0.659574 (-1840 2160);
PAINT MONO (-1840 2160);
DISPLAY INVISIBLE (-1840 2160);
FORCEPROP 2 LAST CDS_LIB pure_quanta_power
J 0
(-1800 2150);
DISPLAY INVISIBLE (-1800 2150);
FORCEPROP 1 LAST HDL_POWER GND
R 1
J 1
(-1725 2175);
DISPLAY 0.872340 (-1725 2175);
PAINT GREEN (-1725 2175);
DISPLAY INVISIBLE (-1725 2175);
FORCEPROP 1 LAST PATH I121
R 1
J 0
(-1800 2225);
DISPLAY 0.872340 (-1800 2225);
PAINT AQUA (-1800 2225);
DISPLAY INVISIBLE (-1800 2225);
FORCEADD Q_RES..2
(-1450 3700);
FORCEPROP 1 LAST LOCATION R1377
J 0
(-1405 3825);
DISPLAY 0.787234 (-1405 3825);
PAINT WHITE (-1405 3825);
FORCEPROP 0 LAST $SEC 1
J 0
(-1400 3875);
DISPLAY 0.680851 (-1400 3875);
PAINT MONO (-1400 3875);
DISPLAY INVISIBLE (-1400 3875);
FORCEPROP 0 LAST CDS_SEC 1
J 0
(-1400 3875);
DISPLAY 0.680851 (-1400 3875);
DISPLAY INVISIBLE (-1400 3875);
FORCEPROP 1 LASTPIN (-1450 3800) $PN 1
J 0
(-1445 3762);
DISPLAY 0.787234 (-1445 3762);
PAINT MONO (-1445 3762);
FORCEPROP 1 LASTPIN (-1450 3600) $PN 2
J 0
(-1445 3610);
DISPLAY 0.787234 (-1445 3610);
PAINT MONO (-1445 3610);
FORCEPROP 1 LAST PACK_TYPE 0201LF
J 0
(-1410 3525);
DISPLAY 0.787234 (-1410 3525);
FORCEPROP 1 LAST TOLERANCE 1%
J 0
(-1405 3725);
DISPLAY 0.787234 (-1405 3725);
FORCEPROP 1 LAST WATTAGE 1/20W
J 0
(-1410 3675);
DISPLAY 0.787234 (-1410 3675);
FORCEPROP 1 LAST MATERIAL EMPTY
J 0
(-1410 3625);
DISPLAY 0.787234 (-1410 3625);
PAINT RED (-1410 3625);
FORCEPROP 1 LAST VALUE 1K
J 0
(-1405 3775);
DISPLAY 0.787234 (-1405 3775);
FORCEPROP 2 LAST CDS_LIB pure_quanta
J 0
(-1450 3700);
DISPLAY INVISIBLE (-1450 3700);
FORCEPROP 1 LAST PATH I125
J 0
(-1400 3875);
DISPLAY 0.978723 (-1400 3875);
PAINT WHITE (-1400 3875);
DISPLAY INVISIBLE (-1400 3875);
FORCEPROP 1 LAST PART_NUMBER CS21001FE07
J 0
(-1410 3575);
DISPLAY 0.978723 (-1410 3575);
DISPLAY INVISIBLE (-1410 3575);
FORCEADD Q_RES..2
(-1450 3175);
FORCEPROP 1 LAST LOCATION R1378
J 0
(-1405 3300);
DISPLAY 0.787234 (-1405 3300);
PAINT WHITE (-1405 3300);
FORCEPROP 0 LAST $SEC 1
J 0
(-1400 3350);
DISPLAY 0.680851 (-1400 3350);
PAINT MONO (-1400 3350);
DISPLAY INVISIBLE (-1400 3350);
FORCEPROP 0 LAST CDS_SEC 1
J 0
(-1400 3350);
DISPLAY 0.680851 (-1400 3350);
DISPLAY INVISIBLE (-1400 3350);
FORCEPROP 1 LASTPIN (-1450 3275) $PN 1
J 0
(-1445 3237);
DISPLAY 0.787234 (-1445 3237);
PAINT MONO (-1445 3237);
FORCEPROP 1 LASTPIN (-1450 3075) $PN 2
J 0
(-1445 3085);
DISPLAY 0.787234 (-1445 3085);
PAINT MONO (-1445 3085);
FORCEPROP 1 LAST PACK_TYPE 0201LF
J 0
(-1410 3000);
DISPLAY 0.787234 (-1410 3000);
FORCEPROP 1 LAST WATTAGE 1/20W
J 0
(-1410 3150);
DISPLAY 0.787234 (-1410 3150);
FORCEPROP 1 LAST VALUE 10K
J 0
(-1405 3250);
DISPLAY 0.787234 (-1405 3250);
FORCEPROP 1 LAST TOLERANCE 1%
J 0
(-1405 3200);
DISPLAY 0.787234 (-1405 3200);
FORCEPROP 1 LAST MATERIAL CHIP
J 0
(-1410 3100);
DISPLAY 0.787234 (-1410 3100);
FORCEPROP 2 LAST CDS_LIB pure_quanta
J 0
(-1450 3175);
DISPLAY INVISIBLE (-1450 3175);
FORCEPROP 1 LAST PATH I126
J 0
(-1400 3350);
DISPLAY 0.978723 (-1400 3350);
PAINT WHITE (-1400 3350);
DISPLAY INVISIBLE (-1400 3350);
FORCEPROP 1 LAST PART_NUMBER CS31001FE17
J 0
(-1410 3050);
DISPLAY 0.510638 (-1410 3050);
DISPLAY INVISIBLE (-1410 3050);
FORCEADD GND..1
(-1450 2775);
FORCEPROP 3 LASTPIN (-1450 2825) SIG_NAME GND\g
J 0
(-1440 2835);
DISPLAY 0.659574 (-1440 2835);
PAINT MONO (-1440 2835);
DISPLAY INVISIBLE (-1440 2835);
FORCEPROP 2 LAST BOM_COST MEM
J 0
(-1550 2850);
DISPLAY 0.808511 (-1550 2850);
DISPLAY INVISIBLE (-1550 2850);
FORCEPROP 1 LAST SIZE 1B
J 0
(-1375 2725);
DISPLAY 0.851064 (-1375 2725);
PAINT GREEN (-1375 2725);
DISPLAY INVISIBLE (-1375 2725);
FORCEPROP 2 LAST CDS_LIB pure_quanta_power
J 0
(-1450 2775);
DISPLAY INVISIBLE (-1450 2775);
FORCEPROP 1 LAST HDL_POWER GND
J 0
(-1450 2925);
DISPLAY 0.851064 (-1450 2925);
PAINT GREEN (-1450 2925);
DISPLAY INVISIBLE (-1450 2925);
FORCEPROP 1 LAST PATH I127
J 0
(-1375 2775);
DISPLAY 0.872340 (-1375 2775);
PAINT AQUA (-1375 2775);
DISPLAY INVISIBLE (-1375 2775);
FORCEADD OFFPAGE..1
R 2
(-600 3425);
FORCEPROP 2 LAST $XR0 332 
J 0
(-414 3425);
DISPLAY 0.638298 (-414 3425);
PAINT MONO (-414 3425);
FORCEPROP 2 LAST CDS_LIB standard
J 0
(-600 3425);
DISPLAY INVISIBLE (-600 3425);
FORCEPROP 1 LAST OFFPAGE TRUE
J 2
(-925 3300);
DISPLAY 0.872340 (-925 3300);
DISPLAY INVISIBLE (-925 3300);
FORCEPROP 1 LAST COMMENT_BODY TRUE
J 2
(-725 3325);
DISPLAY 0.872340 (-725 3325);
PAINT GREEN (-725 3325);
DISPLAY INVISIBLE (-725 3325);
FORCEPROP 2 LAST PATH I128
J 0
(-425 3500);
DISPLAY 0.680851 (-425 3500);
DISPLAY INVISIBLE (-425 3500);
FORCEADD P1V0..1
(-1450 4100);
FORCEPROP 3 LASTPIN (-1450 4050) SIG_NAME P1V8_CPU1_RT_1D\g
J 0
(-1440 4060);
DISPLAY 0.659574 (-1440 4060);
PAINT MONO (-1440 4060);
DISPLAY INVISIBLE (-1440 4060);
FORCEPROP 1 LAST HDL_POWER P1V8_CPU1_RT_1D
J 1
(-1450 4150);
DISPLAY 0.489362 (-1450 4150);
PAINT SKYBLUE (-1450 4150);
FORCEPROP 2 LAST CDS_LIB pure_quanta_power
J 0
(-1450 4100);
DISPLAY INVISIBLE (-1450 4100);
FORCEPROP 1 LAST PATH I129
J 0
(-1400 4125);
DISPLAY 0.872340 (-1400 4125);
PAINT AQUA (-1400 4125);
DISPLAY INVISIBLE (-1400 4125);
FORCEADD UNIVERSAL_GND..1
R 1
(-1800 3100);
FORCEPROP 3 LASTPIN (-1850 3100) SIG_NAME GND\g
J 0
(-1840 3110);
DISPLAY 0.659574 (-1840 3110);
PAINT MONO (-1840 3110);
DISPLAY INVISIBLE (-1840 3110);
FORCEPROP 2 LAST CDS_LIB pure_quanta_power
J 0
(-1800 3100);
DISPLAY INVISIBLE (-1800 3100);
FORCEPROP 1 LAST HDL_POWER GND
R 1
J 1
(-1725 3125);
DISPLAY 0.872340 (-1725 3125);
PAINT GREEN (-1725 3125);
DISPLAY INVISIBLE (-1725 3125);
FORCEPROP 1 LAST PATH I130
R 1
J 0
(-1800 3175);
DISPLAY 0.872340 (-1800 3175);
PAINT AQUA (-1800 3175);
DISPLAY INVISIBLE (-1800 3175);
FORCEADD Q_RES..2
(-8825 3300);
FORCEPROP 1 LAST LOCATION R756
J 0
(-8780 3425);
DISPLAY 0.978723 (-8780 3425);
PAINT WHITE (-8780 3425);
FORCEPROP 0 LAST $SEC 1
J 0
(-8775 3475);
DISPLAY 0.680851 (-8775 3475);
PAINT MONO (-8775 3475);
DISPLAY INVISIBLE (-8775 3475);
FORCEPROP 0 LAST CDS_SEC 1
J 0
(-8775 3475);
DISPLAY 0.680851 (-8775 3475);
DISPLAY INVISIBLE (-8775 3475);
FORCEPROP 1 LASTPIN (-8825 3400) $PN 1
J 0
(-8820 3362);
DISPLAY 0.787234 (-8820 3362);
PAINT MONO (-8820 3362);
FORCEPROP 1 LASTPIN (-8825 3200) $PN 2
J 0
(-8820 3210);
DISPLAY 0.787234 (-8820 3210);
PAINT MONO (-8820 3210);
FORCEPROP 1 LAST PACK_TYPE 0201LF
J 0
(-8785 3125);
DISPLAY 0.978723 (-8785 3125);
FORCEPROP 1 LAST TOLERANCE 1%
J 0
(-8780 3325);
DISPLAY 0.978723 (-8780 3325);
FORCEPROP 1 LAST VALUE 200
J 0
(-8780 3375);
DISPLAY 0.978723 (-8780 3375);
FORCEPROP 1 LAST MATERIAL CHIP
J 0
(-8785 3225);
DISPLAY 0.978723 (-8785 3225);
FORCEPROP 1 LAST WATTAGE 1/20W
J 0
(-8785 3275);
DISPLAY 0.978723 (-8785 3275);
FORCEPROP 2 LAST CDS_LIB pure_quanta
J 0
(-8825 3300);
DISPLAY INVISIBLE (-8825 3300);
FORCEPROP 1 LAST PATH I132
J 0
(-8775 3475);
DISPLAY 0.978723 (-8775 3475);
PAINT WHITE (-8775 3475);
DISPLAY INVISIBLE (-8775 3475);
FORCEPROP 1 LAST PART_NUMBER CS12001FE12
J 0
(-8785 3175);
DISPLAY 0.978723 (-8785 3175);
DISPLAY INVISIBLE (-8785 3175);
FORCEADD OFFPAGE..5
(-2625 900);
FORCEPROP 2 LAST $XR0 332 
J 0
(-2880 900);
DISPLAY 0.638298 (-2880 900);
PAINT MONO (-2880 900);
FORCEPROP 2 LAST CDS_LIB standard
J 0
(-2625 900);
DISPLAY INVISIBLE (-2625 900);
FORCEPROP 1 LAST OFFPAGE TRUE
J 0
(-2300 775);
DISPLAY 0.872340 (-2300 775);
PAINT GREEN (-2300 775);
DISPLAY INVISIBLE (-2300 775);
FORCEPROP 1 LAST COMMENT_BODY TRUE
J 0
(-2525 825);
DISPLAY 0.872340 (-2525 825);
PAINT GREEN (-2525 825);
DISPLAY INVISIBLE (-2525 825);
FORCEPROP 2 LAST PATH I133
J 0
(-2575 975);
DISPLAY 0.680851 (-2575 975);
DISPLAY INVISIBLE (-2575 975);
FORCEADD OFFPAGE..5
(-2625 950);
FORCEPROP 2 LAST $XR0 332 
J 0
(-2880 950);
DISPLAY 0.638298 (-2880 950);
PAINT MONO (-2880 950);
FORCEPROP 2 LAST CDS_LIB standard
J 0
(-2625 950);
DISPLAY INVISIBLE (-2625 950);
FORCEPROP 1 LAST OFFPAGE TRUE
J 0
(-2300 825);
DISPLAY 0.872340 (-2300 825);
PAINT GREEN (-2300 825);
DISPLAY INVISIBLE (-2300 825);
FORCEPROP 1 LAST COMMENT_BODY TRUE
J 0
(-2525 875);
DISPLAY 0.872340 (-2525 875);
PAINT GREEN (-2525 875);
DISPLAY INVISIBLE (-2525 875);
FORCEPROP 2 LAST PATH I135
J 0
(-2575 1025);
DISPLAY 0.680851 (-2575 1025);
DISPLAY INVISIBLE (-2575 1025);
FORCEADD OFFPAGE..5
(-2625 1050);
FORCEPROP 2 LAST $XR0 332 
J 0
(-2880 1050);
DISPLAY 0.638298 (-2880 1050);
PAINT MONO (-2880 1050);
FORCEPROP 2 LAST CDS_LIB standard
J 2
(-2625 1050);
DISPLAY INVISIBLE (-2625 1050);
FORCEPROP 1 LAST OFFPAGE TRUE
J 0
(-2300 925);
DISPLAY 0.872340 (-2300 925);
PAINT GREEN (-2300 925);
DISPLAY INVISIBLE (-2300 925);
FORCEPROP 1 LAST COMMENT_BODY TRUE
J 0
(-2525 975);
DISPLAY 0.872340 (-2525 975);
PAINT GREEN (-2525 975);
DISPLAY INVISIBLE (-2525 975);
FORCEPROP 2 LAST PATH I136
J 0
(-2575 1125);
DISPLAY 0.680851 (-2575 1125);
DISPLAY INVISIBLE (-2575 1125);
FORCEADD OFFPAGE..5
(-2625 1000);
FORCEPROP 2 LAST $XR0 332 
J 0
(-2880 1000);
DISPLAY 0.638298 (-2880 1000);
PAINT MONO (-2880 1000);
FORCEPROP 2 LAST CDS_LIB standard
J 0
(-2625 1000);
DISPLAY INVISIBLE (-2625 1000);
FORCEPROP 1 LAST OFFPAGE TRUE
J 0
(-2300 875);
DISPLAY 0.872340 (-2300 875);
PAINT GREEN (-2300 875);
DISPLAY INVISIBLE (-2300 875);
FORCEPROP 1 LAST COMMENT_BODY TRUE
J 0
(-2525 925);
DISPLAY 0.872340 (-2525 925);
PAINT GREEN (-2525 925);
DISPLAY INVISIBLE (-2525 925);
FORCEPROP 2 LAST PATH I137
J 0
(-2575 1075);
DISPLAY 0.680851 (-2575 1075);
DISPLAY INVISIBLE (-2575 1075);
FORCEADD Q_RES..2
(-1475 1300);
FORCEPROP 1 LAST LOCATION R1454
J 0
(-1430 1425);
DISPLAY 0.978723 (-1430 1425);
FORCEPROP 0 LAST $SEC 1
J 0
(-1425 1475);
DISPLAY 0.680851 (-1425 1475);
PAINT MONO (-1425 1475);
DISPLAY INVISIBLE (-1425 1475);
FORCEPROP 0 LAST CDS_SEC 1
J 0
(-1425 1475);
DISPLAY 0.680851 (-1425 1475);
DISPLAY INVISIBLE (-1425 1475);
FORCEPROP 1 LASTPIN (-1475 1400) $PN 1
J 0
(-1470 1362);
DISPLAY 0.787234 (-1470 1362);
PAINT MONO (-1470 1362);
FORCEPROP 1 LASTPIN (-1475 1200) $PN 2
J 0
(-1470 1210);
DISPLAY 0.787234 (-1470 1210);
PAINT MONO (-1470 1210);
FORCEPROP 1 LAST MATERIAL EMPTY
J 0
(-1435 1225);
DISPLAY 0.787234 (-1435 1225);
PAINT RED (-1435 1225);
FORCEPROP 1 LAST VALUE 4.7K
J 0
(-1430 1375);
DISPLAY 0.787234 (-1430 1375);
FORCEPROP 1 LAST TOLERANCE 5%
J 0
(-1430 1325);
DISPLAY 0.787234 (-1430 1325);
FORCEPROP 1 LAST WATTAGE 1/20W
J 0
(-1435 1275);
DISPLAY 0.787234 (-1435 1275);
FORCEPROP 1 LAST PACK_TYPE 0201LF
J 0
(-1425 1150);
DISPLAY 0.787234 (-1425 1150);
FORCEPROP 2 LAST CDS_LIB pure_quanta
J 0
(-1475 1300);
DISPLAY INVISIBLE (-1475 1300);
FORCEPROP 1 LAST PATH I145
J 0
(-1425 1475);
DISPLAY 0.978723 (-1425 1475);
PAINT WHITE (-1425 1475);
DISPLAY INVISIBLE (-1425 1475);
FORCEPROP 1 LAST PART_NUMBER CS24701JE04
J 0
(-1435 1175);
DISPLAY 0.978723 (-1435 1175);
DISPLAY INVISIBLE (-1435 1175);
FORCEADD Q_RES..2
(-1200 1300);
FORCEPROP 1 LAST LOCATION R1455
J 0
(-1155 1425);
DISPLAY 0.978723 (-1155 1425);
FORCEPROP 0 LAST $SEC 1
J 0
(-1150 1475);
DISPLAY 0.680851 (-1150 1475);
PAINT MONO (-1150 1475);
DISPLAY INVISIBLE (-1150 1475);
FORCEPROP 0 LAST CDS_SEC 1
J 0
(-1150 1475);
DISPLAY 0.680851 (-1150 1475);
DISPLAY INVISIBLE (-1150 1475);
FORCEPROP 1 LASTPIN (-1200 1400) $PN 1
J 0
(-1195 1362);
DISPLAY 0.787234 (-1195 1362);
PAINT MONO (-1195 1362);
FORCEPROP 1 LASTPIN (-1200 1200) $PN 2
J 0
(-1195 1210);
DISPLAY 0.787234 (-1195 1210);
PAINT MONO (-1195 1210);
FORCEPROP 1 LAST PACK_TYPE 0201LF
J 0
(-1150 1150);
DISPLAY 0.787234 (-1150 1150);
FORCEPROP 1 LAST MATERIAL EMPTY
J 0
(-1160 1225);
DISPLAY 0.787234 (-1160 1225);
PAINT RED (-1160 1225);
FORCEPROP 1 LAST VALUE 4.7K
J 0
(-1155 1375);
DISPLAY 0.787234 (-1155 1375);
FORCEPROP 1 LAST TOLERANCE 5%
J 0
(-1155 1325);
DISPLAY 0.787234 (-1155 1325);
FORCEPROP 1 LAST WATTAGE 1/20W
J 0
(-1160 1275);
DISPLAY 0.787234 (-1160 1275);
FORCEPROP 2 LAST CDS_LIB pure_quanta
J 0
(-1200 1300);
DISPLAY INVISIBLE (-1200 1300);
FORCEPROP 1 LAST PATH I146
J 0
(-1150 1475);
DISPLAY 0.978723 (-1150 1475);
PAINT WHITE (-1150 1475);
DISPLAY INVISIBLE (-1150 1475);
FORCEPROP 1 LAST PART_NUMBER CS24701JE04
J 0
(-1160 1175);
DISPLAY 0.978723 (-1160 1175);
DISPLAY INVISIBLE (-1160 1175);
FORCEADD GND..1
(-650 375);
FORCEPROP 3 LASTPIN (-650 425) SIG_NAME GND\g
J 0
(-640 435);
DISPLAY 0.659574 (-640 435);
PAINT MONO (-640 435);
DISPLAY INVISIBLE (-640 435);
FORCEPROP 2 LAST CDS_LIB pure_quanta_power
J 0
(-650 375);
DISPLAY INVISIBLE (-650 375);
FORCEPROP 2 LAST BOM_COST MEM
J 0
(-750 450);
DISPLAY 0.808511 (-750 450);
DISPLAY INVISIBLE (-750 450);
FORCEPROP 1 LAST SIZE 1B
J 0
(-575 325);
DISPLAY 0.851064 (-575 325);
PAINT GREEN (-575 325);
DISPLAY INVISIBLE (-575 325);
FORCEPROP 1 LAST HDL_POWER GND
J 0
(-650 525);
DISPLAY 0.851064 (-650 525);
PAINT GREEN (-650 525);
DISPLAY INVISIBLE (-650 525);
FORCEPROP 1 LAST PATH I148
J 0
(-575 375);
DISPLAY 0.872340 (-575 375);
PAINT AQUA (-575 375);
DISPLAY INVISIBLE (-575 375);
FORCEADD OFFPAGE..1
(-7900 900);
FORCEPROP 2 LAST $XR0 183 
J 0
(-8152 900);
DISPLAY 0.638298 (-8152 900);
PAINT MONO (-8152 900);
FORCEPROP 2 LAST CDS_LIB standard
J 0
(-7900 900);
DISPLAY INVISIBLE (-7900 900);
FORCEPROP 1 LAST OFFPAGE TRUE
J 0
(-7575 775);
DISPLAY 0.872340 (-7575 775);
DISPLAY INVISIBLE (-7575 775);
FORCEPROP 1 LAST COMMENT_BODY TRUE
J 0
(-7775 800);
DISPLAY 0.872340 (-7775 800);
PAINT GREEN (-7775 800);
DISPLAY INVISIBLE (-7775 800);
FORCEPROP 2 LAST PATH I15
J 0
(-8175 950);
DISPLAY 0.680851 (-8175 950);
DISPLAY INVISIBLE (-8175 950);
FORCEADD Q_RES..2
(-650 675);
FORCEPROP 1 LAST LOCATION R1373
J 0
(-605 800);
DISPLAY 0.787234 (-605 800);
FORCEPROP 0 LAST $SEC 1
J 0
(-600 850);
DISPLAY 0.680851 (-600 850);
PAINT MONO (-600 850);
DISPLAY INVISIBLE (-600 850);
FORCEPROP 0 LAST CDS_SEC 1
J 0
(-600 850);
DISPLAY 0.680851 (-600 850);
DISPLAY INVISIBLE (-600 850);
FORCEPROP 1 LASTPIN (-650 775) $PN 1
J 0
(-645 737);
DISPLAY 0.787234 (-645 737);
PAINT MONO (-645 737);
FORCEPROP 1 LASTPIN (-650 575) $PN 2
J 0
(-645 585);
DISPLAY 0.787234 (-645 585);
PAINT MONO (-645 585);
FORCEPROP 1 LAST MATERIAL CHIP
J 0
(-610 600);
DISPLAY 0.787234 (-610 600);
FORCEPROP 1 LAST PACK_TYPE 0201LF
J 0
(-610 500);
DISPLAY 0.787234 (-610 500);
FORCEPROP 1 LAST VALUE 4.7K
J 0
(-605 750);
DISPLAY 0.787234 (-605 750);
FORCEPROP 1 LAST TOLERANCE 5%
J 0
(-605 700);
DISPLAY 0.787234 (-605 700);
FORCEPROP 1 LAST WATTAGE 1/20W
J 0
(-610 650);
DISPLAY 0.787234 (-610 650);
FORCEPROP 2 LAST CDS_LIB pure_quanta
J 0
(-650 675);
DISPLAY INVISIBLE (-650 675);
FORCEPROP 1 LAST PATH I150
J 0
(-600 850);
DISPLAY 0.978723 (-600 850);
PAINT WHITE (-600 850);
DISPLAY INVISIBLE (-600 850);
FORCEPROP 1 LAST PART_NUMBER CS24701JE04
J 0
(-610 550);
DISPLAY 0.978723 (-610 550);
DISPLAY INVISIBLE (-610 550);
FORCEADD Q_RES..2
(-650 1325);
FORCEPROP 1 LAST LOCATION R1461
J 0
(-605 1450);
DISPLAY 0.787234 (-605 1450);
FORCEPROP 0 LAST $SEC 1
J 0
(-600 1500);
DISPLAY 0.680851 (-600 1500);
PAINT MONO (-600 1500);
DISPLAY INVISIBLE (-600 1500);
FORCEPROP 0 LAST CDS_SEC 1
J 0
(-600 1500);
DISPLAY 0.680851 (-600 1500);
DISPLAY INVISIBLE (-600 1500);
FORCEPROP 1 LASTPIN (-650 1425) $PN 1
J 0
(-645 1387);
DISPLAY 0.787234 (-645 1387);
PAINT MONO (-645 1387);
FORCEPROP 1 LASTPIN (-650 1225) $PN 2
J 0
(-645 1235);
DISPLAY 0.787234 (-645 1235);
PAINT MONO (-645 1235);
FORCEPROP 1 LAST PACK_TYPE 0201LF
J 0
(-600 1175);
DISPLAY 0.787234 (-600 1175);
FORCEPROP 1 LAST MATERIAL EMPTY
J 0
(-610 1250);
DISPLAY 0.787234 (-610 1250);
PAINT RED (-610 1250);
FORCEPROP 1 LAST WATTAGE 1/20W
J 0
(-610 1300);
DISPLAY 0.787234 (-610 1300);
FORCEPROP 1 LAST TOLERANCE 5%
J 0
(-605 1350);
DISPLAY 0.787234 (-605 1350);
FORCEPROP 1 LAST VALUE 4.7K
J 0
(-605 1400);
DISPLAY 0.787234 (-605 1400);
FORCEPROP 2 LAST CDS_LIB pure_quanta
J 2
(-650 1325);
DISPLAY INVISIBLE (-650 1325);
FORCEPROP 1 LAST PATH I151
J 0
(-600 1500);
DISPLAY 0.978723 (-600 1500);
PAINT WHITE (-600 1500);
DISPLAY INVISIBLE (-600 1500);
FORCEPROP 1 LAST PART_NUMBER CS24701JE04
J 0
(-610 1200);
DISPLAY 0.978723 (-610 1200);
DISPLAY INVISIBLE (-610 1200);
FORCEADD P1V0..1
(-650 1625);
FORCEPROP 3 LASTPIN (-650 1575) SIG_NAME P1V8_CPU1_RT_1D\g
J 0
(-640 1585);
DISPLAY 0.659574 (-640 1585);
PAINT MONO (-640 1585);
DISPLAY INVISIBLE (-640 1585);
FORCEPROP 1 LAST HDL_POWER P1V8_CPU1_RT_1D
J 1
(-650 1675);
DISPLAY 0.489362 (-650 1675);
PAINT SKYBLUE (-650 1675);
FORCEPROP 2 LAST CDS_LIB pure_quanta_power
J 0
(-650 1625);
DISPLAY INVISIBLE (-650 1625);
FORCEPROP 1 LAST PATH I152
J 0
(-600 1650);
DISPLAY 0.872340 (-600 1650);
PAINT AQUA (-600 1650);
DISPLAY INVISIBLE (-600 1650);
FORCEADD Q_RES..2
(-925 1300);
FORCEPROP 1 LAST LOCATION R1456
J 0
(-880 1425);
DISPLAY 0.978723 (-880 1425);
FORCEPROP 0 LAST $SEC 1
J 0
(-875 1475);
DISPLAY 0.680851 (-875 1475);
PAINT MONO (-875 1475);
DISPLAY INVISIBLE (-875 1475);
FORCEPROP 0 LAST CDS_SEC 1
J 0
(-875 1475);
DISPLAY 0.680851 (-875 1475);
DISPLAY INVISIBLE (-875 1475);
FORCEPROP 1 LASTPIN (-925 1400) $PN 1
J 0
(-920 1362);
DISPLAY 0.787234 (-920 1362);
PAINT MONO (-920 1362);
FORCEPROP 1 LASTPIN (-925 1200) $PN 2
J 0
(-920 1210);
DISPLAY 0.787234 (-920 1210);
PAINT MONO (-920 1210);
FORCEPROP 1 LAST PACK_TYPE 0201LF
J 0
(-885 1125);
DISPLAY 0.787234 (-885 1125);
FORCEPROP 1 LAST MATERIAL EMPTY
J 0
(-885 1225);
DISPLAY 0.787234 (-885 1225);
PAINT RED (-885 1225);
FORCEPROP 1 LAST WATTAGE 1/20W
J 0
(-885 1275);
DISPLAY 0.787234 (-885 1275);
FORCEPROP 1 LAST VALUE 1K
J 0
(-880 1375);
DISPLAY 0.787234 (-880 1375);
FORCEPROP 1 LAST TOLERANCE 1%
J 0
(-880 1325);
DISPLAY 0.787234 (-880 1325);
FORCEPROP 2 LAST CDS_LIB pure_quanta
J 0
(-925 1300);
DISPLAY INVISIBLE (-925 1300);
FORCEPROP 1 LAST PATH I153
J 0
(-875 1475);
DISPLAY 0.978723 (-875 1475);
PAINT WHITE (-875 1475);
DISPLAY INVISIBLE (-875 1475);
FORCEPROP 1 LAST PART_NUMBER CS21001FE07
J 0
(-885 1175);
DISPLAY 0.978723 (-885 1175);
DISPLAY INVISIBLE (-885 1175);
FORCEADD OFFPAGE..1
R 2
(-2575 3500);
FORCEPROP 2 LAST $XR0 332 
J 0
(-2389 3500);
DISPLAY 0.638298 (-2389 3500);
PAINT MONO (-2389 3500);
FORCEPROP 2 LAST CDS_LIB standard
J 0
(-2575 3500);
DISPLAY INVISIBLE (-2575 3500);
FORCEPROP 1 LAST OFFPAGE TRUE
J 2
(-2900 3375);
DISPLAY 0.872340 (-2900 3375);
DISPLAY INVISIBLE (-2900 3375);
FORCEPROP 1 LAST COMMENT_BODY TRUE
J 2
(-2700 3400);
DISPLAY 0.872340 (-2700 3400);
PAINT GREEN (-2700 3400);
DISPLAY INVISIBLE (-2700 3400);
FORCEPROP 2 LAST PATH I155
J 0
(-2400 3575);
DISPLAY 0.680851 (-2400 3575);
DISPLAY INVISIBLE (-2400 3575);
FORCEADD OFFPAGE..1
R 2
(-2575 3400);
FORCEPROP 2 LAST $XR0 332 
J 0
(-2389 3400);
DISPLAY 0.638298 (-2389 3400);
PAINT MONO (-2389 3400);
FORCEPROP 2 LAST CDS_LIB standard
J 0
(-2575 3400);
DISPLAY INVISIBLE (-2575 3400);
FORCEPROP 1 LAST OFFPAGE TRUE
J 2
(-2900 3275);
DISPLAY 0.872340 (-2900 3275);
DISPLAY INVISIBLE (-2900 3275);
FORCEPROP 1 LAST COMMENT_BODY TRUE
J 2
(-2700 3300);
DISPLAY 0.872340 (-2700 3300);
PAINT GREEN (-2700 3300);
DISPLAY INVISIBLE (-2700 3300);
FORCEPROP 2 LAST PATH I156
J 0
(-2400 3475);
DISPLAY 0.680851 (-2400 3475);
DISPLAY INVISIBLE (-2400 3475);
FORCEADD OFFPAGE..1
R 2
(-2575 3300);
FORCEPROP 2 LAST $XR0 332 
J 0
(-2389 3300);
DISPLAY 0.638298 (-2389 3300);
PAINT MONO (-2389 3300);
FORCEPROP 2 LAST CDS_LIB standard
J 0
(-2575 3300);
DISPLAY INVISIBLE (-2575 3300);
FORCEPROP 1 LAST OFFPAGE TRUE
J 2
(-2900 3175);
DISPLAY 0.872340 (-2900 3175);
DISPLAY INVISIBLE (-2900 3175);
FORCEPROP 1 LAST COMMENT_BODY TRUE
J 2
(-2700 3200);
DISPLAY 0.872340 (-2700 3200);
PAINT GREEN (-2700 3200);
DISPLAY INVISIBLE (-2700 3200);
FORCEPROP 2 LAST PATH I157
J 0
(-2400 3375);
DISPLAY 0.680851 (-2400 3375);
DISPLAY INVISIBLE (-2400 3375);
FORCEADD OFFPAGE..1
R 2
(-2600 3200);
FORCEPROP 2 LAST $XR0 332 
J 0
(-2414 3200);
DISPLAY 0.638298 (-2414 3200);
PAINT MONO (-2414 3200);
FORCEPROP 2 LAST CDS_LIB standard
J 0
(-2600 3200);
DISPLAY INVISIBLE (-2600 3200);
FORCEPROP 1 LAST OFFPAGE TRUE
J 2
(-2925 3075);
DISPLAY 0.872340 (-2925 3075);
DISPLAY INVISIBLE (-2925 3075);
FORCEPROP 1 LAST COMMENT_BODY TRUE
J 2
(-2725 3100);
DISPLAY 0.872340 (-2725 3100);
PAINT GREEN (-2725 3100);
DISPLAY INVISIBLE (-2725 3100);
FORCEPROP 2 LAST PATH I158
J 0
(-2425 3275);
DISPLAY 0.680851 (-2425 3275);
DISPLAY INVISIBLE (-2425 3275);
FORCEADD OFFPAGE..1
(-7900 1050);
FORCEPROP 2 LAST $XR0 183 
J 0
(-8152 1050);
DISPLAY 0.638298 (-8152 1050);
PAINT MONO (-8152 1050);
FORCEPROP 2 LAST CDS_LIB standard
J 0
(-7900 1050);
DISPLAY INVISIBLE (-7900 1050);
FORCEPROP 1 LAST OFFPAGE TRUE
J 0
(-7575 925);
DISPLAY 0.872340 (-7575 925);
DISPLAY INVISIBLE (-7575 925);
FORCEPROP 1 LAST COMMENT_BODY TRUE
J 0
(-7775 950);
DISPLAY 0.872340 (-7775 950);
PAINT GREEN (-7775 950);
DISPLAY INVISIBLE (-7775 950);
FORCEPROP 2 LAST PATH I16
J 0
(-8175 1100);
DISPLAY 0.680851 (-8175 1100);
DISPLAY INVISIBLE (-8175 1100);
FORCEADD UNIVERSAL_GND..1
(-8825 3025);
FORCEPROP 3 LASTPIN (-8825 3075) SIG_NAME GND\g
J 0
(-8815 3085);
DISPLAY 0.659574 (-8815 3085);
PAINT MONO (-8815 3085);
DISPLAY INVISIBLE (-8815 3085);
FORCEPROP 2 LAST CDS_LIB pure_quanta_power
J 0
(-8825 3025);
DISPLAY INVISIBLE (-8825 3025);
FORCEPROP 1 LAST HDL_POWER GND
J 1
(-8800 2950);
DISPLAY 0.872340 (-8800 2950);
PAINT GREEN (-8800 2950);
DISPLAY INVISIBLE (-8800 2950);
FORCEPROP 1 LAST PATH I17
J 0
(-8750 3025);
DISPLAY 0.872340 (-8750 3025);
PAINT AQUA (-8750 3025);
DISPLAY INVISIBLE (-8750 3025);
FORCEADD Q_RES..2
(-8825 3975);
FORCEPROP 1 LAST LOCATION R755
J 0
(-8780 4100);
DISPLAY 0.787234 (-8780 4100);
FORCEPROP 0 LAST $SEC 1
J 0
(-8775 4150);
DISPLAY 0.680851 (-8775 4150);
PAINT MONO (-8775 4150);
DISPLAY INVISIBLE (-8775 4150);
FORCEPROP 0 LAST CDS_SEC 1
J 0
(-8775 4150);
DISPLAY 0.680851 (-8775 4150);
DISPLAY INVISIBLE (-8775 4150);
FORCEPROP 1 LASTPIN (-8825 4075) $PN 1
J 0
(-8820 4037);
DISPLAY 0.787234 (-8820 4037);
PAINT MONO (-8820 4037);
FORCEPROP 1 LASTPIN (-8825 3875) $PN 2
J 0
(-8820 3885);
DISPLAY 0.787234 (-8820 3885);
PAINT MONO (-8820 3885);
FORCEPROP 1 LAST VALUE 4.7K
J 0
(-8780 4050);
DISPLAY 0.787234 (-8780 4050);
FORCEPROP 1 LAST WATTAGE 1/20W
J 0
(-8785 3950);
DISPLAY 0.787234 (-8785 3950);
FORCEPROP 1 LAST MATERIAL EMPTY
J 0
(-8785 3900);
DISPLAY 0.787234 (-8785 3900);
FORCEPROP 1 LAST PACK_TYPE 0201LF
J 0
(-8775 3825);
DISPLAY 0.787234 (-8775 3825);
FORCEPROP 1 LAST TOLERANCE 5%
J 0
(-8780 4000);
DISPLAY 0.787234 (-8780 4000);
FORCEPROP 2 LAST CDS_LIB pure_quanta
J 0
(-8825 3975);
DISPLAY INVISIBLE (-8825 3975);
FORCEPROP 1 LAST PATH I19
J 0
(-8775 4150);
DISPLAY 0.978723 (-8775 4150);
PAINT WHITE (-8775 4150);
DISPLAY INVISIBLE (-8775 4150);
FORCEPROP 1 LAST PART_NUMBER CS24701JE04
J 0
(-8785 3850);
DISPLAY 0.978723 (-8785 3850);
DISPLAY INVISIBLE (-8785 3850);
FORCEADD P1V0..1
(-8825 4300);
FORCEPROP 3 LASTPIN (-8825 4250) SIG_NAME P1V8_CPU1_RT_1D\g
J 0
(-8815 4260);
DISPLAY 0.659574 (-8815 4260);
PAINT MONO (-8815 4260);
DISPLAY INVISIBLE (-8815 4260);
FORCEPROP 1 LAST HDL_POWER P1V8_CPU1_RT_1D
J 1
(-8825 4350);
DISPLAY 0.489362 (-8825 4350);
PAINT SKYBLUE (-8825 4350);
FORCEPROP 2 LAST CDS_LIB pure_quanta_power
J 0
(-8825 4300);
DISPLAY INVISIBLE (-8825 4300);
FORCEPROP 1 LAST PATH I20
J 0
(-8775 4325);
DISPLAY 0.872340 (-8775 4325);
PAINT AQUA (-8775 4325);
DISPLAY INVISIBLE (-8775 4325);
FORCEADD Q_RES..2
(-8800 4900);
FORCEPROP 1 LAST LOCATION R782
J 0
(-8755 5025);
DISPLAY 0.787234 (-8755 5025);
FORCEPROP 0 LAST $SEC 1
J 0
(-8750 5075);
DISPLAY 0.680851 (-8750 5075);
PAINT MONO (-8750 5075);
DISPLAY INVISIBLE (-8750 5075);
FORCEPROP 0 LAST CDS_SEC 1
J 0
(-8750 5075);
DISPLAY 0.680851 (-8750 5075);
DISPLAY INVISIBLE (-8750 5075);
FORCEPROP 1 LASTPIN (-8800 5000) $PN 1
J 0
(-8795 4962);
DISPLAY 0.787234 (-8795 4962);
PAINT MONO (-8795 4962);
FORCEPROP 1 LASTPIN (-8800 4800) $PN 2
J 0
(-8795 4810);
DISPLAY 0.787234 (-8795 4810);
PAINT MONO (-8795 4810);
FORCEPROP 1 LAST PACK_TYPE 0201LF
J 0
(-8760 4725);
DISPLAY 0.787234 (-8760 4725);
FORCEPROP 1 LAST MATERIAL CHIP
J 0
(-8760 4825);
DISPLAY 0.787234 (-8760 4825);
FORCEPROP 1 LAST WATTAGE 1/20W
J 0
(-8760 4875);
DISPLAY 0.787234 (-8760 4875);
FORCEPROP 1 LAST TOLERANCE 1%
J 0
(-8755 4925);
DISPLAY 0.787234 (-8755 4925);
FORCEPROP 1 LAST VALUE 10K
J 0
(-8755 4975);
DISPLAY 0.787234 (-8755 4975);
FORCEPROP 2 LAST CDS_LIB pure_quanta
J 0
(-8800 4900);
DISPLAY INVISIBLE (-8800 4900);
FORCEPROP 1 LAST PATH I21
J 0
(-8750 5075);
DISPLAY 0.978723 (-8750 5075);
PAINT WHITE (-8750 5075);
DISPLAY INVISIBLE (-8750 5075);
FORCEPROP 1 LAST PART_NUMBER CS31001FE17
J 0
(-8760 4775);
DISPLAY 0.638298 (-8760 4775);
DISPLAY INVISIBLE (-8760 4775);
FORCEADD Q_RES..2
(-8500 4900);
FORCEPROP 1 LAST LOCATION R783
J 0
(-8455 5025);
DISPLAY 0.787234 (-8455 5025);
FORCEPROP 0 LAST $SEC 1
J 0
(-8450 5075);
DISPLAY 0.680851 (-8450 5075);
PAINT MONO (-8450 5075);
DISPLAY INVISIBLE (-8450 5075);
FORCEPROP 0 LAST CDS_SEC 1
J 0
(-8450 5075);
DISPLAY 0.680851 (-8450 5075);
DISPLAY INVISIBLE (-8450 5075);
FORCEPROP 1 LASTPIN (-8500 5000) $PN 1
J 0
(-8495 4962);
DISPLAY 0.787234 (-8495 4962);
PAINT MONO (-8495 4962);
FORCEPROP 1 LASTPIN (-8500 4800) $PN 2
J 0
(-8495 4810);
DISPLAY 0.787234 (-8495 4810);
PAINT MONO (-8495 4810);
FORCEPROP 1 LAST PACK_TYPE 0201LF
J 0
(-8460 4725);
DISPLAY 0.787234 (-8460 4725);
FORCEPROP 1 LAST MATERIAL CHIP
J 0
(-8460 4825);
DISPLAY 0.787234 (-8460 4825);
FORCEPROP 1 LAST WATTAGE 1/20W
J 0
(-8460 4875);
DISPLAY 0.787234 (-8460 4875);
FORCEPROP 1 LAST TOLERANCE 1%
J 0
(-8455 4925);
DISPLAY 0.787234 (-8455 4925);
FORCEPROP 1 LAST VALUE 10K
J 0
(-8455 4975);
DISPLAY 0.787234 (-8455 4975);
FORCEPROP 2 LAST CDS_LIB pure_quanta
J 0
(-8500 4900);
DISPLAY INVISIBLE (-8500 4900);
FORCEPROP 1 LAST PATH I22
J 0
(-8450 5075);
DISPLAY 0.978723 (-8450 5075);
PAINT WHITE (-8450 5075);
DISPLAY INVISIBLE (-8450 5075);
FORCEPROP 1 LAST PART_NUMBER CS31001FE17
J 0
(-8460 4775);
DISPLAY 0.510638 (-8460 4775);
DISPLAY INVISIBLE (-8460 4775);
FORCEADD Q_RES..2
(-8175 4900);
FORCEPROP 1 LAST LOCATION R785
J 0
(-8130 5025);
DISPLAY 0.787234 (-8130 5025);
FORCEPROP 0 LAST $SEC 1
J 0
(-8125 5075);
DISPLAY 0.680851 (-8125 5075);
PAINT MONO (-8125 5075);
DISPLAY INVISIBLE (-8125 5075);
FORCEPROP 0 LAST CDS_SEC 1
J 0
(-8125 5075);
DISPLAY 0.680851 (-8125 5075);
DISPLAY INVISIBLE (-8125 5075);
FORCEPROP 1 LASTPIN (-8175 5000) $PN 1
J 0
(-8170 4962);
DISPLAY 0.787234 (-8170 4962);
PAINT MONO (-8170 4962);
FORCEPROP 1 LASTPIN (-8175 4800) $PN 2
J 0
(-8170 4810);
DISPLAY 0.787234 (-8170 4810);
PAINT MONO (-8170 4810);
FORCEPROP 1 LAST MATERIAL CHIP
J 0
(-8135 4825);
DISPLAY 0.787234 (-8135 4825);
FORCEPROP 1 LAST PACK_TYPE 0201LF
J 0
(-8135 4725);
DISPLAY 0.787234 (-8135 4725);
FORCEPROP 1 LAST WATTAGE 1/20W
J 0
(-8135 4875);
DISPLAY 0.787234 (-8135 4875);
FORCEPROP 1 LAST TOLERANCE 5%
J 0
(-8130 4925);
DISPLAY 0.787234 (-8130 4925);
FORCEPROP 1 LAST VALUE 4.7K
J 0
(-8130 4975);
DISPLAY 0.787234 (-8130 4975);
FORCEPROP 2 LAST CDS_LIB pure_quanta
J 0
(-8175 4900);
DISPLAY INVISIBLE (-8175 4900);
FORCEPROP 1 LAST PATH I23
J 0
(-8125 5075);
DISPLAY 0.978723 (-8125 5075);
PAINT WHITE (-8125 5075);
DISPLAY INVISIBLE (-8125 5075);
FORCEPROP 1 LAST PART_NUMBER CS24701JE04
J 0
(-8135 4775);
DISPLAY 0.978723 (-8135 4775);
DISPLAY INVISIBLE (-8135 4775);
FORCEADD Q_RES..2
(-8800 5850);
FORCEPROP 1 LAST LOCATION R781
J 0
(-8755 5975);
DISPLAY 0.787234 (-8755 5975);
FORCEPROP 0 LAST $SEC 1
J 0
(-8750 6025);
DISPLAY 0.680851 (-8750 6025);
PAINT MONO (-8750 6025);
DISPLAY INVISIBLE (-8750 6025);
FORCEPROP 0 LAST CDS_SEC 1
J 0
(-8750 6025);
DISPLAY 0.680851 (-8750 6025);
DISPLAY INVISIBLE (-8750 6025);
FORCEPROP 1 LASTPIN (-8800 5950) $PN 1
J 0
(-8795 5912);
DISPLAY 0.787234 (-8795 5912);
PAINT MONO (-8795 5912);
FORCEPROP 1 LASTPIN (-8800 5750) $PN 2
J 0
(-8795 5760);
DISPLAY 0.787234 (-8795 5760);
PAINT MONO (-8795 5760);
FORCEPROP 1 LAST MATERIAL EMPTY
J 0
(-8760 5775);
DISPLAY 0.787234 (-8760 5775);
FORCEPROP 1 LAST PACK_TYPE 0201LF
J 0
(-8750 5700);
DISPLAY 0.787234 (-8750 5700);
FORCEPROP 1 LAST WATTAGE 1/20W
J 0
(-8760 5825);
DISPLAY 0.787234 (-8760 5825);
FORCEPROP 1 LAST VALUE 4.7K
J 0
(-8755 5925);
DISPLAY 0.787234 (-8755 5925);
FORCEPROP 1 LAST TOLERANCE 5%
J 0
(-8755 5875);
DISPLAY 0.787234 (-8755 5875);
FORCEPROP 2 LAST CDS_LIB pure_quanta
J 0
(-8800 5850);
DISPLAY INVISIBLE (-8800 5850);
FORCEPROP 1 LAST PATH I24
J 0
(-8750 6025);
DISPLAY 0.978723 (-8750 6025);
PAINT WHITE (-8750 6025);
DISPLAY INVISIBLE (-8750 6025);
FORCEPROP 1 LAST PART_NUMBER CS24701JE04
J 0
(-8760 5725);
DISPLAY 0.978723 (-8760 5725);
DISPLAY INVISIBLE (-8760 5725);
FORCEADD Q_RES..2
(-8175 5850);
FORCEPROP 1 LAST LOCATION R784
J 0
(-8130 5975);
DISPLAY 0.787234 (-8130 5975);
FORCEPROP 0 LAST $SEC 1
J 0
(-8125 6025);
DISPLAY 0.680851 (-8125 6025);
PAINT MONO (-8125 6025);
DISPLAY INVISIBLE (-8125 6025);
FORCEPROP 0 LAST CDS_SEC 1
J 0
(-8125 6025);
DISPLAY 0.680851 (-8125 6025);
DISPLAY INVISIBLE (-8125 6025);
FORCEPROP 1 LASTPIN (-8175 5950) $PN 1
J 0
(-8170 5912);
DISPLAY 0.787234 (-8170 5912);
PAINT MONO (-8170 5912);
FORCEPROP 1 LASTPIN (-8175 5750) $PN 2
J 0
(-8170 5760);
DISPLAY 0.787234 (-8170 5760);
PAINT MONO (-8170 5760);
FORCEPROP 1 LAST VALUE 4.7K
J 0
(-8130 5925);
DISPLAY 0.787234 (-8130 5925);
FORCEPROP 1 LAST WATTAGE 1/20W
J 0
(-8135 5825);
DISPLAY 0.787234 (-8135 5825);
FORCEPROP 1 LAST MATERIAL EMPTY
J 0
(-8135 5775);
DISPLAY 0.787234 (-8135 5775);
FORCEPROP 1 LAST PACK_TYPE 0201LF
J 0
(-8125 5700);
DISPLAY 0.787234 (-8125 5700);
FORCEPROP 1 LAST TOLERANCE 5%
J 0
(-8130 5875);
DISPLAY 0.787234 (-8130 5875);
FORCEPROP 2 LAST CDS_LIB pure_quanta
J 0
(-8175 5850);
DISPLAY INVISIBLE (-8175 5850);
FORCEPROP 1 LAST PATH I25
J 0
(-8125 6025);
DISPLAY 0.978723 (-8125 6025);
PAINT WHITE (-8125 6025);
DISPLAY INVISIBLE (-8125 6025);
FORCEPROP 1 LAST PART_NUMBER CS24701JE04
J 0
(-8135 5725);
DISPLAY 0.978723 (-8135 5725);
DISPLAY INVISIBLE (-8135 5725);
FORCEADD P1V0..1
(-8800 6250);
FORCEPROP 3 LASTPIN (-8800 6200) SIG_NAME P1V8_CPU1_RT_1D\g
J 0
(-8790 6210);
DISPLAY 0.659574 (-8790 6210);
PAINT MONO (-8790 6210);
DISPLAY INVISIBLE (-8790 6210);
FORCEPROP 1 LAST HDL_POWER P1V8_CPU1_RT_1D
J 1
(-8800 6300);
DISPLAY 0.489362 (-8800 6300);
PAINT SKYBLUE (-8800 6300);
FORCEPROP 2 LAST CDS_LIB pure_quanta_power
J 0
(-8800 6250);
DISPLAY INVISIBLE (-8800 6250);
FORCEPROP 1 LAST PATH I26
J 0
(-8750 6275);
DISPLAY 0.872340 (-8750 6275);
PAINT AQUA (-8750 6275);
DISPLAY INVISIBLE (-8750 6275);
FORCEADD OFFPAGE..3
R 2
(-7500 1400);
FORCEPROP 2 LAST $XR1 186 
J 0
(-7930 1400);
DISPLAY 0.638298 (-7930 1400);
PAINT MONO (-7930 1400);
FORCEPROP 2 LAST $XR0 185 
J 0
(-7810 1400);
DISPLAY 0.638298 (-7810 1400);
PAINT MONO (-7810 1400);
FORCEPROP 2 LAST CDS_LIB standard
J 0
(-7500 1400);
DISPLAY INVISIBLE (-7500 1400);
FORCEPROP 1 LAST OFFPAGE TRUE
J 2
(-7825 1275);
DISPLAY 0.872340 (-7825 1275);
PAINT GREEN (-7825 1275);
DISPLAY INVISIBLE (-7825 1275);
FORCEPROP 1 LAST COMMENT_BODY TRUE
J 2
(-7450 1300);
DISPLAY 0.872340 (-7450 1300);
PAINT GREEN (-7450 1300);
DISPLAY INVISIBLE (-7450 1300);
FORCEPROP 2 LAST PATH I27
J 0
(-7775 1450);
DISPLAY 0.680851 (-7775 1450);
DISPLAY INVISIBLE (-7775 1450);
FORCEADD OFFPAGE..5
(-7500 1500);
FORCEPROP 2 LAST $XR1 186 
J 0
(-7905 1500);
DISPLAY 0.638298 (-7905 1500);
PAINT MONO (-7905 1500);
FORCEPROP 2 LAST $XR0 185 
J 0
(-7785 1500);
DISPLAY 0.638298 (-7785 1500);
PAINT MONO (-7785 1500);
FORCEPROP 2 LAST CDS_LIB standard
J 0
(-7500 1500);
DISPLAY INVISIBLE (-7500 1500);
FORCEPROP 1 LAST OFFPAGE TRUE
J 0
(-7175 1375);
DISPLAY 0.872340 (-7175 1375);
PAINT GREEN (-7175 1375);
DISPLAY INVISIBLE (-7175 1375);
FORCEPROP 1 LAST COMMENT_BODY TRUE
J 0
(-7400 1425);
DISPLAY 0.872340 (-7400 1425);
PAINT GREEN (-7400 1425);
DISPLAY INVISIBLE (-7400 1425);
FORCEPROP 2 LAST PATH I28
J 0
(-7750 1550);
DISPLAY 0.680851 (-7750 1550);
DISPLAY INVISIBLE (-7750 1550);
FORCEADD UNIVERSAL_GND..1
(-6150 250);
FORCEPROP 3 LASTPIN (-6150 300) SIG_NAME GND\g
J 0
(-6140 310);
DISPLAY 0.659574 (-6140 310);
PAINT MONO (-6140 310);
DISPLAY INVISIBLE (-6140 310);
FORCEPROP 2 LAST CDS_LIB pure_quanta_power
J 0
(-6150 250);
DISPLAY INVISIBLE (-6150 250);
FORCEPROP 1 LAST HDL_POWER GND
J 1
(-6125 175);
DISPLAY 0.872340 (-6125 175);
PAINT GREEN (-6125 175);
DISPLAY INVISIBLE (-6125 175);
FORCEPROP 1 LAST PATH I29
J 0
(-6075 250);
DISPLAY 0.872340 (-6075 250);
PAINT AQUA (-6075 250);
DISPLAY INVISIBLE (-6075 250);
FORCEADD UNIVERSAL_GND..1
(-6000 250);
FORCEPROP 3 LASTPIN (-6000 300) SIG_NAME GND\g
J 0
(-5990 310);
DISPLAY 0.659574 (-5990 310);
PAINT MONO (-5990 310);
DISPLAY INVISIBLE (-5990 310);
FORCEPROP 2 LAST CDS_LIB pure_quanta_power
J 0
(-6000 250);
DISPLAY INVISIBLE (-6000 250);
FORCEPROP 1 LAST HDL_POWER GND
J 1
(-5975 175);
DISPLAY 0.872340 (-5975 175);
PAINT GREEN (-5975 175);
DISPLAY INVISIBLE (-5975 175);
FORCEPROP 1 LAST PATH I30
J 0
(-5925 250);
DISPLAY 0.872340 (-5925 250);
PAINT AQUA (-5925 250);
DISPLAY INVISIBLE (-5925 250);
FORCEADD Q_RES..2
R 2
(-6150 575);
FORCEPROP 1 LAST LOCATION R625
J 2
(-6195 700);
DISPLAY 0.978723 (-6195 700);
PAINT SKYBLUE (-6195 700);
FORCEPROP 0 LAST $SEC 1
J 0
(-6175 750);
DISPLAY 0.680851 (-6175 750);
PAINT MONO (-6175 750);
DISPLAY INVISIBLE (-6175 750);
FORCEPROP 0 LAST CDS_SEC 1
J 0
(-6175 750);
DISPLAY 0.680851 (-6175 750);
DISPLAY INVISIBLE (-6175 750);
FORCEPROP 1 LASTPIN (-6150 675) $PN 1
J 2
(-6155 637);
DISPLAY 0.787234 (-6155 637);
PAINT MONO (-6155 637);
FORCEPROP 1 LASTPIN (-6150 475) $PN 2
J 2
(-6155 485);
DISPLAY 0.787234 (-6155 485);
PAINT MONO (-6155 485);
FORCEPROP 1 LAST MATERIAL EMPTY
J 2
(-6190 500);
DISPLAY 0.978723 (-6190 500);
FORCEPROP 1 LAST PACK_TYPE 0201LF
J 2
(-6190 400);
DISPLAY 0.978723 (-6190 400);
FORCEPROP 1 LAST WATTAGE 1/20W
J 2
(-6190 550);
DISPLAY 0.978723 (-6190 550);
FORCEPROP 1 LAST TOLERANCE 1%
J 2
(-6195 600);
DISPLAY 0.978723 (-6195 600);
FORCEPROP 1 LAST VALUE 51.1
J 2
(-6195 650);
DISPLAY 0.978723 (-6195 650);
FORCEPROP 2 LAST CDS_LIB pure_quanta
J 0
(-6150 575);
DISPLAY INVISIBLE (-6150 575);
FORCEPROP 1 LAST PATH I31
J 2
(-6200 750);
DISPLAY 0.978723 (-6200 750);
PAINT WHITE (-6200 750);
DISPLAY INVISIBLE (-6200 750);
FORCEPROP 1 LAST PART_NUMBER CS05111FE00
J 2
(-6190 450);
DISPLAY 0.978723 (-6190 450);
DISPLAY INVISIBLE (-6190 450);
FORCEADD Q_RES..2
(-6000 575);
FORCEPROP 1 LAST LOCATION R626
J 0
(-5955 700);
DISPLAY 0.978723 (-5955 700);
PAINT SKYBLUE (-5955 700);
FORCEPROP 0 LAST $SEC 1
J 0
(-5950 750);
DISPLAY 0.680851 (-5950 750);
PAINT MONO (-5950 750);
DISPLAY INVISIBLE (-5950 750);
FORCEPROP 0 LAST CDS_SEC 1
J 0
(-5950 750);
DISPLAY 0.680851 (-5950 750);
DISPLAY INVISIBLE (-5950 750);
FORCEPROP 1 LASTPIN (-6000 675) $PN 1
J 0
(-5995 637);
DISPLAY 0.787234 (-5995 637);
PAINT MONO (-5995 637);
FORCEPROP 1 LASTPIN (-6000 475) $PN 2
J 0
(-5995 485);
DISPLAY 0.787234 (-5995 485);
PAINT MONO (-5995 485);
FORCEPROP 1 LAST PACK_TYPE 0201LF
J 0
(-5960 400);
DISPLAY 0.978723 (-5960 400);
FORCEPROP 1 LAST MATERIAL EMPTY
J 0
(-5960 500);
DISPLAY 0.978723 (-5960 500);
FORCEPROP 1 LAST WATTAGE 1/20W
J 0
(-5960 550);
DISPLAY 0.978723 (-5960 550);
FORCEPROP 1 LAST VALUE 51.1
J 0
(-5955 650);
DISPLAY 0.978723 (-5955 650);
FORCEPROP 1 LAST TOLERANCE 1%
J 0
(-5955 600);
DISPLAY 0.978723 (-5955 600);
FORCEPROP 2 LAST CDS_LIB pure_quanta
J 0
(-6000 575);
DISPLAY INVISIBLE (-6000 575);
FORCEPROP 1 LAST PATH I32
J 0
(-5950 750);
DISPLAY 0.978723 (-5950 750);
PAINT WHITE (-5950 750);
DISPLAY INVISIBLE (-5950 750);
FORCEPROP 1 LAST PART_NUMBER CS05111FE00
J 0
(-5960 450);
DISPLAY 0.978723 (-5960 450);
DISPLAY INVISIBLE (-5960 450);
FORCEADD Q_RES..1
(-6450 1050);
FORCEPROP 1 LAST LOCATION R597
J 0
(-6700 1050);
DISPLAY 0.978723 (-6700 1050);
PAINT SKYBLUE (-6700 1050);
FORCEPROP 2 LAST SEC 1
J 0
(-6500 1250);
DISPLAY 0.680851 (-6500 1250);
PAINT MONO (-6500 1250);
DISPLAY INVISIBLE (-6500 1250);
FORCEPROP 1 LASTPIN (-6550 1050) $PN 1
J 0
(-6538 1062);
DISPLAY 0.787234 (-6538 1062);
PAINT MONO (-6538 1062);
FORCEPROP 1 LASTPIN (-6350 1050) $PN 2
J 0
(-6388 1062);
DISPLAY 0.787234 (-6388 1062);
PAINT MONO (-6388 1062);
FORCEPROP 1 LAST PACK_TYPE 0201LF
J 0
(-6425 1125);
DISPLAY 0.787234 (-6425 1125);
FORCEPROP 1 LAST MATERIAL CHIP
J 0
(-6625 1125);
DISPLAY 0.787234 (-6625 1125);
FORCEPROP 1 LAST WATTAGE 1/20W
J 2
(-6650 1125);
DISPLAY 0.787234 (-6650 1125);
FORCEPROP 1 LAST VALUE 0
J 2
(-6650 1175);
DISPLAY 0.787234 (-6650 1175);
FORCEPROP 1 LAST TOLERANCE 5%
J 0
(-6625 1175);
DISPLAY 0.787234 (-6625 1175);
FORCEPROP 0 LAST SEC_TYPE 0201LF
J 0
(-6500 1250);
DISPLAY 0.680851 (-6500 1250);
DISPLAY INVISIBLE (-6500 1250);
FORCEPROP 2 LAST CDS_LIB pure_quanta
J 0
(-6450 1050);
DISPLAY INVISIBLE (-6450 1050);
FORCEPROP 1 LAST PATH I33
J 0
(-6500 1200);
DISPLAY 0.978723 (-6500 1200);
PAINT WHITE (-6500 1200);
DISPLAY INVISIBLE (-6500 1200);
FORCEPROP 1 LAST PART_NUMBER CS00001JE10
J 0
(-6500 1175);
DISPLAY 0.808511 (-6500 1175);
DISPLAY INVISIBLE (-6500 1175);
FORCEADD Q_RES..1
(-6450 900);
FORCEPROP 1 LAST LOCATION R598
J 0
(-6700 900);
DISPLAY 0.978723 (-6700 900);
PAINT SKYBLUE (-6700 900);
FORCEPROP 2 LAST SEC 1
J 0
(-6500 1100);
DISPLAY 0.680851 (-6500 1100);
PAINT MONO (-6500 1100);
DISPLAY INVISIBLE (-6500 1100);
FORCEPROP 1 LASTPIN (-6550 900) $PN 1
J 0
(-6538 912);
DISPLAY 0.787234 (-6538 912);
PAINT MONO (-6538 912);
FORCEPROP 1 LASTPIN (-6350 900) $PN 2
J 0
(-6388 912);
DISPLAY 0.787234 (-6388 912);
PAINT MONO (-6388 912);
FORCEPROP 1 LAST PACK_TYPE 0201LF
J 0
(-6425 975);
DISPLAY 0.787234 (-6425 975);
FORCEPROP 1 LAST MATERIAL CHIP
J 0
(-6625 975);
DISPLAY 0.787234 (-6625 975);
FORCEPROP 2 LAST SEC_TYPE 0201LF
J 0
(-6500 1100);
DISPLAY 0.680851 (-6500 1100);
DISPLAY INVISIBLE (-6500 1100);
FORCEPROP 1 LAST WATTAGE 1/20W
J 2
(-6650 975);
DISPLAY 0.787234 (-6650 975);
DISPLAY INVISIBLE (-6650 975);
FORCEPROP 1 LAST VALUE 0
J 2
(-6650 1025);
DISPLAY 0.787234 (-6650 1025);
DISPLAY INVISIBLE (-6650 1025);
FORCEPROP 1 LAST TOLERANCE 5%
J 0
(-6625 1025);
DISPLAY 0.787234 (-6625 1025);
DISPLAY INVISIBLE (-6625 1025);
FORCEPROP 2 LAST CDS_LIB pure_quanta
J 0
(-6450 900);
DISPLAY INVISIBLE (-6450 900);
FORCEPROP 1 LAST PATH I34
J 0
(-6500 1050);
DISPLAY 0.978723 (-6500 1050);
PAINT WHITE (-6500 1050);
DISPLAY INVISIBLE (-6500 1050);
FORCEPROP 1 LAST PART_NUMBER CS00001JE10
J 0
(-6500 1025);
DISPLAY 0.808511 (-6500 1025);
DISPLAY INVISIBLE (-6500 1025);
FORCEADD Q_RES..1
(-6175 1400);
FORCEPROP 1 LAST LOCATION R671
J 0
(-6425 1425);
DISPLAY 0.978723 (-6425 1425);
PAINT SKYBLUE (-6425 1425);
FORCEPROP 0 LAST $SEC 1
J 0
(-6325 1475);
DISPLAY 0.680851 (-6325 1475);
PAINT MONO (-6325 1475);
DISPLAY INVISIBLE (-6325 1475);
FORCEPROP 0 LAST CDS_SEC 1
J 0
(-6325 1475);
DISPLAY 0.680851 (-6325 1475);
DISPLAY INVISIBLE (-6325 1475);
FORCEPROP 1 LASTPIN (-6275 1400) $PN 1
J 0
(-6263 1412);
DISPLAY 0.787234 (-6263 1412);
PAINT MONO (-6263 1412);
FORCEPROP 1 LASTPIN (-6075 1400) $PN 2
J 0
(-6113 1412);
DISPLAY 0.787234 (-6113 1412);
PAINT MONO (-6113 1412);
FORCEPROP 1 LAST PACK_TYPE 0201LF
J 0
(-6150 1475);
DISPLAY 0.787234 (-6150 1475);
DISPLAY INVISIBLE (-6150 1475);
FORCEPROP 1 LAST WATTAGE 1/20W
J 2
(-6375 1475);
DISPLAY 0.787234 (-6375 1475);
DISPLAY INVISIBLE (-6375 1475);
FORCEPROP 1 LAST MATERIAL CHIP
J 0
(-6350 1475);
DISPLAY 0.787234 (-6350 1475);
DISPLAY INVISIBLE (-6350 1475);
FORCEPROP 2 LAST CDS_LIB pure_quanta
J 0
(-6175 1400);
DISPLAY INVISIBLE (-6175 1400);
FORCEPROP 1 LAST VALUE 49.9
J 2
(-6375 1525);
DISPLAY 0.787234 (-6375 1525);
DISPLAY INVISIBLE (-6375 1525);
FORCEPROP 1 LAST TOLERANCE 1%
J 0
(-6350 1525);
DISPLAY 0.787234 (-6350 1525);
DISPLAY INVISIBLE (-6350 1525);
FORCEPROP 1 LAST PATH I35
J 0
(-6225 1550);
DISPLAY 0.978723 (-6225 1550);
PAINT WHITE (-6225 1550);
DISPLAY INVISIBLE (-6225 1550);
FORCEPROP 1 LAST PART_NUMBER CS04991FE06
J 0
(-6225 1525);
DISPLAY 0.808511 (-6225 1525);
DISPLAY INVISIBLE (-6225 1525);
FORCEADD Q_RES..1
(-6175 1500);
FORCEPROP 1 LAST LOCATION R670
J 0
(-6425 1525);
DISPLAY 0.978723 (-6425 1525);
PAINT SKYBLUE (-6425 1525);
FORCEPROP 0 LAST $SEC 1
J 0
(-6225 1675);
DISPLAY 0.680851 (-6225 1675);
PAINT MONO (-6225 1675);
DISPLAY INVISIBLE (-6225 1675);
FORCEPROP 0 LAST CDS_SEC 1
J 0
(-6225 1675);
DISPLAY 0.680851 (-6225 1675);
DISPLAY INVISIBLE (-6225 1675);
FORCEPROP 1 LASTPIN (-6275 1500) $PN 1
J 0
(-6263 1512);
DISPLAY 0.787234 (-6263 1512);
PAINT MONO (-6263 1512);
FORCEPROP 1 LASTPIN (-6075 1500) $PN 2
J 0
(-6113 1512);
DISPLAY 0.787234 (-6113 1512);
PAINT MONO (-6113 1512);
FORCEPROP 1 LAST WATTAGE 1/20W
J 2
(-6375 1575);
DISPLAY 0.787234 (-6375 1575);
FORCEPROP 1 LAST PACK_TYPE 0201LF
J 0
(-6150 1575);
DISPLAY 0.787234 (-6150 1575);
FORCEPROP 1 LAST MATERIAL CHIP
J 0
(-6350 1575);
DISPLAY 0.787234 (-6350 1575);
FORCEPROP 1 LAST VALUE 49.9
J 2
(-6375 1625);
DISPLAY 0.787234 (-6375 1625);
FORCEPROP 1 LAST TOLERANCE 1%
J 0
(-6350 1625);
DISPLAY 0.787234 (-6350 1625);
FORCEPROP 2 LAST CDS_LIB pure_quanta
J 0
(-6175 1500);
DISPLAY INVISIBLE (-6175 1500);
FORCEPROP 1 LAST PATH I36
J 0
(-6225 1650);
DISPLAY 0.978723 (-6225 1650);
PAINT WHITE (-6225 1650);
DISPLAY INVISIBLE (-6225 1650);
FORCEPROP 1 LAST PART_NUMBER CS04991FE06
J 0
(-6225 1625);
DISPLAY 0.808511 (-6225 1625);
DISPLAY INVISIBLE (-6225 1625);
FORCEADD OFFPAGE..1
(-6000 1800);
FORCEPROP 2 LAST $XR0 332 
J 0
(-6282 1800);
DISPLAY 0.638298 (-6282 1800);
PAINT MONO (-6282 1800);
FORCEPROP 2 LAST CDS_LIB standard
J 0
(-6000 1800);
DISPLAY INVISIBLE (-6000 1800);
FORCEPROP 1 LAST OFFPAGE TRUE
J 0
(-5675 1675);
DISPLAY 0.872340 (-5675 1675);
DISPLAY INVISIBLE (-5675 1675);
FORCEPROP 1 LAST COMMENT_BODY TRUE
J 0
(-5875 1700);
DISPLAY 0.872340 (-5875 1700);
PAINT GREEN (-5875 1700);
DISPLAY INVISIBLE (-5875 1700);
FORCEPROP 2 LAST PATH I37
J 0
(-6250 1850);
DISPLAY 0.680851 (-6250 1850);
DISPLAY INVISIBLE (-6250 1850);
FORCEADD OFFPAGE..3
R 2
(-7500 2650);
FORCEPROP 2 LAST $XR0 184 
J 0
(-7810 2650);
DISPLAY 0.638298 (-7810 2650);
PAINT MONO (-7810 2650);
FORCEPROP 2 LAST CDS_LIB standard
J 0
(-7500 2650);
DISPLAY INVISIBLE (-7500 2650);
FORCEPROP 1 LAST OFFPAGE TRUE
J 2
(-7825 2525);
DISPLAY 0.872340 (-7825 2525);
PAINT GREEN (-7825 2525);
DISPLAY INVISIBLE (-7825 2525);
FORCEPROP 1 LAST COMMENT_BODY TRUE
J 2
(-7450 2550);
DISPLAY 0.872340 (-7450 2550);
PAINT GREEN (-7450 2550);
DISPLAY INVISIBLE (-7450 2550);
FORCEPROP 2 LAST PATH I38
J 0
(-7775 2700);
DISPLAY 0.680851 (-7775 2700);
DISPLAY INVISIBLE (-7775 2700);
FORCEADD OFFPAGE..1
(-7500 2750);
FORCEPROP 2 LAST $XR0 184 
J 0
(-7752 2750);
DISPLAY 0.638298 (-7752 2750);
PAINT MONO (-7752 2750);
FORCEPROP 2 LAST CDS_LIB standard
J 0
(-7500 2750);
DISPLAY INVISIBLE (-7500 2750);
FORCEPROP 1 LAST OFFPAGE TRUE
J 0
(-7175 2625);
DISPLAY 0.872340 (-7175 2625);
DISPLAY INVISIBLE (-7175 2625);
FORCEPROP 1 LAST COMMENT_BODY TRUE
J 0
(-7375 2650);
DISPLAY 0.872340 (-7375 2650);
PAINT GREEN (-7375 2650);
DISPLAY INVISIBLE (-7375 2650);
FORCEPROP 2 LAST PATH I39
J 0
(-7750 2800);
DISPLAY 0.680851 (-7750 2800);
DISPLAY INVISIBLE (-7750 2800);
FORCEADD OFFPAGE..5
R 2
(-7650 3750);
FORCEPROP 2 LAST $XR0 332 
J 0
(-7461 3750);
DISPLAY 0.638298 (-7461 3750);
PAINT MONO (-7461 3750);
FORCEPROP 2 LAST CDS_LIB standard
J 0
(-7650 3750);
DISPLAY INVISIBLE (-7650 3750);
FORCEPROP 1 LAST OFFPAGE TRUE
J 2
(-7975 3625);
DISPLAY 0.872340 (-7975 3625);
PAINT GREEN (-7975 3625);
DISPLAY INVISIBLE (-7975 3625);
FORCEPROP 1 LAST COMMENT_BODY TRUE
J 2
(-7750 3675);
DISPLAY 0.872340 (-7750 3675);
PAINT GREEN (-7750 3675);
DISPLAY INVISIBLE (-7750 3675);
FORCEPROP 2 LAST PATH I40
J 0
(-7475 3825);
DISPLAY 0.680851 (-7475 3825);
DISPLAY INVISIBLE (-7475 3825);
FORCEADD OFFPAGE..1
(-6000 1900);
FORCEPROP 2 LAST $XR0 332 
J 0
(-6282 1900);
DISPLAY 0.638298 (-6282 1900);
PAINT MONO (-6282 1900);
FORCEPROP 2 LAST CDS_LIB standard
J 0
(-6000 1900);
DISPLAY INVISIBLE (-6000 1900);
FORCEPROP 1 LAST OFFPAGE TRUE
J 0
(-5675 1775);
DISPLAY 0.872340 (-5675 1775);
DISPLAY INVISIBLE (-5675 1775);
FORCEPROP 1 LAST COMMENT_BODY TRUE
J 0
(-5875 1800);
DISPLAY 0.872340 (-5875 1800);
PAINT GREEN (-5875 1800);
DISPLAY INVISIBLE (-5875 1800);
FORCEPROP 2 LAST PATH I41
J 0
(-6250 1950);
DISPLAY 0.680851 (-6250 1950);
DISPLAY INVISIBLE (-6250 1950);
FORCEADD OFFPAGE..1
(-6000 2000);
FORCEPROP 2 LAST $XR0 332 
J 0
(-6282 2000);
DISPLAY 0.638298 (-6282 2000);
PAINT MONO (-6282 2000);
FORCEPROP 2 LAST CDS_LIB standard
J 0
(-6000 2000);
DISPLAY INVISIBLE (-6000 2000);
FORCEPROP 1 LAST OFFPAGE TRUE
J 0
(-5675 1875);
DISPLAY 0.872340 (-5675 1875);
DISPLAY INVISIBLE (-5675 1875);
FORCEPROP 1 LAST COMMENT_BODY TRUE
J 0
(-5875 1900);
DISPLAY 0.872340 (-5875 1900);
PAINT GREEN (-5875 1900);
DISPLAY INVISIBLE (-5875 1900);
FORCEPROP 2 LAST PATH I42
J 0
(-6250 2050);
DISPLAY 0.680851 (-6250 2050);
DISPLAY INVISIBLE (-6250 2050);
FORCEADD Q_RES..1
(-6200 2650);
FORCEPROP 1 LAST LOCATION R780
J 0
(-6450 2675);
DISPLAY 0.978723 (-6450 2675);
FORCEPROP 0 LAST $SEC 1
J 0
(-6450 2725);
DISPLAY 0.680851 (-6450 2725);
PAINT MONO (-6450 2725);
DISPLAY INVISIBLE (-6450 2725);
FORCEPROP 0 LAST CDS_SEC 1
J 0
(-6450 2725);
DISPLAY 0.680851 (-6450 2725);
DISPLAY INVISIBLE (-6450 2725);
FORCEPROP 1 LASTPIN (-6300 2650) $PN 1
J 0
(-6288 2662);
DISPLAY 0.787234 (-6288 2662);
PAINT MONO (-6288 2662);
FORCEPROP 1 LASTPIN (-6100 2650) $PN 2
J 0
(-6138 2662);
DISPLAY 0.787234 (-6138 2662);
PAINT MONO (-6138 2662);
FORCEPROP 1 LAST WATTAGE 1/20W
J 2
(-6400 2725);
DISPLAY 0.787234 (-6400 2725);
DISPLAY INVISIBLE (-6400 2725);
FORCEPROP 1 LAST VALUE 0
J 2
(-6400 2775);
DISPLAY 0.787234 (-6400 2775);
DISPLAY INVISIBLE (-6400 2775);
FORCEPROP 1 LAST TOLERANCE 5%
J 0
(-6375 2775);
DISPLAY 0.787234 (-6375 2775);
DISPLAY INVISIBLE (-6375 2775);
FORCEPROP 1 LAST MATERIAL CHIP
J 0
(-6375 2725);
DISPLAY 0.787234 (-6375 2725);
DISPLAY INVISIBLE (-6375 2725);
FORCEPROP 1 LAST PACK_TYPE 0201LF
J 0
(-6175 2725);
DISPLAY 0.787234 (-6175 2725);
DISPLAY INVISIBLE (-6175 2725);
FORCEPROP 2 LAST CDS_LIB pure_quanta
J 0
(-6200 2650);
DISPLAY INVISIBLE (-6200 2650);
FORCEPROP 1 LAST PATH I43
J 0
(-6250 2800);
DISPLAY 0.978723 (-6250 2800);
PAINT WHITE (-6250 2800);
DISPLAY INVISIBLE (-6250 2800);
FORCEPROP 1 LAST PART_NUMBER CS00001JE10
J 0
(-6250 2775);
DISPLAY 0.808511 (-6250 2775);
DISPLAY INVISIBLE (-6250 2775);
FORCEADD Q_RES..1
(-6200 2750);
FORCEPROP 1 LAST LOCATION R779
J 0
(-6450 2775);
DISPLAY 0.978723 (-6450 2775);
FORCEPROP 0 LAST $SEC 1
J 0
(-6250 2925);
DISPLAY 0.680851 (-6250 2925);
PAINT MONO (-6250 2925);
DISPLAY INVISIBLE (-6250 2925);
FORCEPROP 0 LAST CDS_SEC 1
J 0
(-6250 2925);
DISPLAY 0.680851 (-6250 2925);
DISPLAY INVISIBLE (-6250 2925);
FORCEPROP 1 LASTPIN (-6300 2750) $PN 1
J 0
(-6288 2762);
DISPLAY 0.787234 (-6288 2762);
PAINT MONO (-6288 2762);
FORCEPROP 1 LASTPIN (-6100 2750) $PN 2
J 0
(-6138 2762);
DISPLAY 0.787234 (-6138 2762);
PAINT MONO (-6138 2762);
FORCEPROP 1 LAST PACK_TYPE 0201LF
J 0
(-6175 2825);
DISPLAY 0.787234 (-6175 2825);
FORCEPROP 1 LAST VALUE 0
J 2
(-6400 2875);
DISPLAY 0.787234 (-6400 2875);
FORCEPROP 1 LAST MATERIAL CHIP
J 0
(-6375 2825);
DISPLAY 0.787234 (-6375 2825);
FORCEPROP 1 LAST TOLERANCE 5%
J 0
(-6375 2875);
DISPLAY 0.787234 (-6375 2875);
FORCEPROP 1 LAST WATTAGE 1/20W
J 2
(-6400 2825);
DISPLAY 0.787234 (-6400 2825);
FORCEPROP 2 LAST CDS_LIB pure_quanta
J 0
(-6200 2750);
DISPLAY INVISIBLE (-6200 2750);
FORCEPROP 1 LAST PATH I44
J 0
(-6250 2900);
DISPLAY 0.978723 (-6250 2900);
PAINT WHITE (-6250 2900);
DISPLAY INVISIBLE (-6250 2900);
FORCEPROP 1 LAST PART_NUMBER CS00001JE10
J 0
(-6250 2875);
DISPLAY 0.808511 (-6250 2875);
DISPLAY INVISIBLE (-6250 2875);
FORCEADD OFFPAGE..1
(-5875 3200);
FORCEPROP 2 LAST $XR0 332 
J 0
(-6127 3200);
DISPLAY 0.638298 (-6127 3200);
PAINT MONO (-6127 3200);
FORCEPROP 2 LAST CDS_LIB standard
J 0
(-5875 3200);
DISPLAY INVISIBLE (-5875 3200);
FORCEPROP 1 LAST OFFPAGE TRUE
J 0
(-5550 3075);
DISPLAY 0.872340 (-5550 3075);
DISPLAY INVISIBLE (-5550 3075);
FORCEPROP 1 LAST COMMENT_BODY TRUE
J 0
(-5750 3100);
DISPLAY 0.872340 (-5750 3100);
PAINT GREEN (-5750 3100);
DISPLAY INVISIBLE (-5750 3100);
FORCEPROP 2 LAST PATH I45
J 0
(-6150 3250);
DISPLAY 0.680851 (-6150 3250);
DISPLAY INVISIBLE (-6150 3250);
FORCEADD OFFPAGE..1
(-5875 3100);
FORCEPROP 2 LAST $XR0 332 
J 0
(-6127 3100);
DISPLAY 0.638298 (-6127 3100);
PAINT MONO (-6127 3100);
FORCEPROP 2 LAST CDS_LIB standard
J 0
(-5875 3100);
DISPLAY INVISIBLE (-5875 3100);
FORCEPROP 1 LAST OFFPAGE TRUE
J 0
(-5550 2975);
DISPLAY 0.872340 (-5550 2975);
DISPLAY INVISIBLE (-5550 2975);
FORCEPROP 1 LAST COMMENT_BODY TRUE
J 0
(-5750 3000);
DISPLAY 0.872340 (-5750 3000);
PAINT GREEN (-5750 3000);
DISPLAY INVISIBLE (-5750 3000);
FORCEPROP 2 LAST PATH I46
J 0
(-6150 3150);
DISPLAY 0.680851 (-6150 3150);
DISPLAY INVISIBLE (-6150 3150);
FORCEADD PT5161LRS..3
(-4225 2200);
FORCEPROP 1 LAST LOCATION U6015
J 0
(-4725 3825);
DISPLAY 0.723404 (-4725 3825);
PAINT GREEN (-4725 3825);
FORCEPROP 0 LAST $SEC 3
J 0
(-4725 3975);
DISPLAY 0.680851 (-4725 3975);
PAINT MONO (-4725 3975);
DISPLAY INVISIBLE (-4725 3975);
FORCEPROP 0 LAST CDS_SEC 3
J 0
(-4725 3975);
DISPLAY 0.680851 (-4725 3975);
DISPLAY INVISIBLE (-4725 3975);
FORCEPROP 0 LASTPIN (-3625 2150) $PN G35
J 0
(-3615 2160);
DISPLAY 0.680851 (-3615 2160);
PAINT MONO (-3615 2160);
FORCEPROP 0 LASTPIN (-4875 1500) $PN FF5
J 2
(-4885 1510);
DISPLAY 0.680851 (-4885 1510);
PAINT MONO (-4885 1510);
FORCEPROP 0 LASTPIN (-4875 1400) $PN FJ3
J 2
(-4885 1410);
DISPLAY 0.680851 (-4885 1410);
PAINT MONO (-4885 1410);
FORCEPROP 0 LASTPIN (-4875 3400) $PN FJ6
J 2
(-4885 3410);
DISPLAY 0.680851 (-4885 3410);
PAINT MONO (-4885 3410);
FORCEPROP 0 LASTPIN (-4875 3300) $PN FJ23
J 2
(-4885 3310);
DISPLAY 0.680851 (-4885 3310);
PAINT MONO (-4885 3310);
FORCEPROP 0 LASTPIN (-4875 3200) $PN FJ25
J 2
(-4885 3210);
DISPLAY 0.680851 (-4885 3210);
PAINT MONO (-4885 3210);
FORCEPROP 0 LASTPIN (-4875 3100) $PN FJ28
J 2
(-4885 3110);
DISPLAY 0.680851 (-4885 3110);
PAINT MONO (-4885 3110);
FORCEPROP 0 LASTPIN (-3625 1750) $PN FJ31
J 0
(-3615 1760);
DISPLAY 0.680851 (-3615 1760);
PAINT MONO (-3615 1760);
FORCEPROP 0 LASTPIN (-3625 3500) $PN B3
J 0
(-3615 3510);
DISPLAY 0.680851 (-3615 3510);
PAINT MONO (-3615 3510);
FORCEPROP 0 LASTPIN (-3625 3200) $PN B6
J 0
(-3615 3210);
DISPLAY 0.680851 (-3615 3210);
PAINT MONO (-3615 3210);
FORCEPROP 0 LASTPIN (-3625 3400) $PN B9
J 0
(-3615 3410);
DISPLAY 0.680851 (-3615 3410);
PAINT MONO (-3615 3410);
FORCEPROP 0 LASTPIN (-3625 2950) $PN FF8
J 0
(-3615 2960);
DISPLAY 0.680851 (-3615 2960);
PAINT MONO (-3615 2960);
FORCEPROP 0 LASTPIN (-3625 3300) $PN B12
J 0
(-3615 3310);
DISPLAY 0.680851 (-3615 3310);
PAINT MONO (-3615 3310);
FORCEPROP 0 LASTPIN (-3625 3100) $PN E8
J 0
(-3615 3110);
DISPLAY 0.680851 (-3615 3110);
PAINT MONO (-3615 3110);
FORCEPROP 0 LASTPIN (-3625 2650) $PN FJ9
J 0
(-3615 2660);
DISPLAY 0.680851 (-3615 2660);
PAINT MONO (-3615 2660);
FORCEPROP 0 LASTPIN (-3625 2050) $PN F2
J 0
(-3615 2060);
DISPLAY 0.680851 (-3615 2060);
PAINT MONO (-3615 2060);
FORCEPROP 0 LASTPIN (-3625 900) $PN E18
J 0
(-3615 910);
DISPLAY 0.680851 (-3615 910);
PAINT MONO (-3615 910);
FORCEPROP 0 LASTPIN (-3625 1050) $PN B16
J 0
(-3615 1060);
DISPLAY 0.680851 (-3615 1060);
PAINT MONO (-3615 1060);
FORCEPROP 0 LASTPIN (-4875 900) $PN FF18
J 2
(-4885 910);
DISPLAY 0.680851 (-4885 910);
PAINT MONO (-4885 910);
FORCEPROP 0 LASTPIN (-4875 1050) $PN FJ16
J 2
(-4885 1060);
DISPLAY 0.680851 (-4885 1060);
PAINT MONO (-4885 1060);
FORCEPROP 0 LASTPIN (-3625 1950) $PN FF11
J 0
(-3615 1960);
DISPLAY 0.680851 (-3615 1960);
PAINT MONO (-3615 1960);
FORCEPROP 0 LASTPIN (-3625 2550) $PN E11
J 0
(-3615 2560);
DISPLAY 0.680851 (-3615 2560);
PAINT MONO (-3615 2560);
FORCEPROP 0 LASTPIN (-3625 2450) $PN FF33
J 0
(-3615 2460);
DISPLAY 0.680851 (-3615 2460);
PAINT MONO (-3615 2460);
FORCEPROP 0 LASTPIN (-4875 2500) $PN F34
J 2
(-4885 2510);
DISPLAY 0.680851 (-4885 2510);
PAINT MONO (-4885 2510);
FORCEPROP 0 LASTPIN (-4875 2400) $PN B23
J 2
(-4885 2410);
DISPLAY 0.680851 (-4885 2410);
PAINT MONO (-4885 2410);
FORCEPROP 0 LASTPIN (-4875 2300) $PN B25
J 2
(-4885 2310);
DISPLAY 0.680851 (-4885 2310);
PAINT MONO (-4885 2310);
FORCEPROP 0 LASTPIN (-4875 2750) $PN B31
J 2
(-4885 2760);
DISPLAY 0.680851 (-4885 2760);
PAINT MONO (-4885 2760);
FORCEPROP 0 LASTPIN (-4875 2650) $PN B28
J 2
(-4885 2660);
DISPLAY 0.680851 (-4885 2660);
PAINT MONO (-4885 2660);
FORCEPROP 0 LASTPIN (-3625 1550) $PN E30
J 0
(-3615 1560);
DISPLAY 0.680851 (-3615 1560);
PAINT MONO (-3615 1560);
FORCEPROP 0 LASTPIN (-4875 2000) $PN FF24
J 2
(-4885 2010);
DISPLAY 0.680851 (-4885 2010);
PAINT MONO (-4885 2010);
FORCEPROP 0 LASTPIN (-4875 1900) $PN FF27
J 2
(-4885 1910);
DISPLAY 0.680851 (-4885 1910);
PAINT MONO (-4885 1910);
FORCEPROP 0 LASTPIN (-4875 1800) $PN FF30
J 2
(-4885 1810);
DISPLAY 0.680851 (-4885 1810);
PAINT MONO (-4885 1810);
FORCEPROP 2 LAST PART_TYPE SMLF
J 0
(-4725 3925);
DISPLAY 0.680851 (-4725 3925);
FORCEPROP 2 LAST VALUE PT5161LRS
J 0
(-4725 3875);
DISPLAY 0.680851 (-4725 3875);
FORCEPROP 1 LAST MATERIAL IC
J 0
(-4725 3675);
DISPLAY 0.723404 (-4725 3675);
PAINT GREEN (-4725 3675);
FORCEPROP 2 LAST CDS_LIB pure_quanta
J 0
(-4225 2200);
DISPLAY INVISIBLE (-4225 2200);
FORCEPROP 1 LAST CDS_LMAN_SYM_OUTLINE -500,1450,450,-1400
J 0
(-4225 2200);
DISPLAY 0.468085 (-4225 2200);
PAINT GREEN (-4225 2200);
DISPLAY INVISIBLE (-4225 2200);
FORCEPROP 1 LAST NEEDS_NO_SIZE TRUE
J 0
(-4225 2200);
DISPLAY 0.723404 (-4225 2200);
PAINT GREEN (-4225 2200);
DISPLAY INVISIBLE (-4225 2200);
FORCEPROP 1 LAST PATH I47
J 0
(-4225 2200);
DISPLAY 0.723404 (-4225 2200);
PAINT GREEN (-4225 2200);
DISPLAY INVISIBLE (-4225 2200);
FORCEPROP 1 LAST PART_NUMBER AJ051610U03
J 0
(-4725 3750);
DISPLAY 0.723404 (-4725 3750);
PAINT GREEN (-4725 3750);
DISPLAY INVISIBLE (-4725 3750);
FORCEADD OFFPAGE..1
(-5825 2300);
FORCEPROP 2 LAST $XR0 332 
J 0
(-6077 2300);
DISPLAY 0.638298 (-6077 2300);
PAINT MONO (-6077 2300);
FORCEPROP 2 LAST CDS_LIB standard
J 0
(-5825 2300);
DISPLAY INVISIBLE (-5825 2300);
FORCEPROP 1 LAST OFFPAGE TRUE
J 0
(-5500 2175);
DISPLAY 0.872340 (-5500 2175);
DISPLAY INVISIBLE (-5500 2175);
FORCEPROP 1 LAST COMMENT_BODY TRUE
J 0
(-5700 2200);
DISPLAY 0.872340 (-5700 2200);
PAINT GREEN (-5700 2200);
DISPLAY INVISIBLE (-5700 2200);
FORCEPROP 2 LAST PATH I48
J 0
(-5775 2375);
DISPLAY 0.680851 (-5775 2375);
DISPLAY INVISIBLE (-5775 2375);
FORCEADD OFFPAGE..1
(-5825 2400);
FORCEPROP 2 LAST $XR0 332 
J 0
(-6077 2400);
DISPLAY 0.638298 (-6077 2400);
PAINT MONO (-6077 2400);
FORCEPROP 2 LAST CDS_LIB standard
J 0
(-5825 2400);
DISPLAY INVISIBLE (-5825 2400);
FORCEPROP 1 LAST OFFPAGE TRUE
J 0
(-5500 2275);
DISPLAY 0.872340 (-5500 2275);
DISPLAY INVISIBLE (-5500 2275);
FORCEPROP 1 LAST COMMENT_BODY TRUE
J 0
(-5700 2300);
DISPLAY 0.872340 (-5700 2300);
PAINT GREEN (-5700 2300);
DISPLAY INVISIBLE (-5700 2300);
FORCEPROP 2 LAST PATH I49
J 0
(-5775 2475);
DISPLAY 0.680851 (-5775 2475);
DISPLAY INVISIBLE (-5775 2475);
FORCEADD OFFPAGE..1
(-5825 2500);
FORCEPROP 2 LAST $XR0 332 
J 0
(-6077 2500);
DISPLAY 0.638298 (-6077 2500);
PAINT MONO (-6077 2500);
FORCEPROP 2 LAST CDS_LIB standard
J 0
(-5825 2500);
DISPLAY INVISIBLE (-5825 2500);
FORCEPROP 1 LAST OFFPAGE TRUE
J 0
(-5500 2375);
DISPLAY 0.872340 (-5500 2375);
DISPLAY INVISIBLE (-5500 2375);
FORCEPROP 1 LAST COMMENT_BODY TRUE
J 0
(-5700 2400);
DISPLAY 0.872340 (-5700 2400);
PAINT GREEN (-5700 2400);
DISPLAY INVISIBLE (-5700 2400);
FORCEPROP 2 LAST PATH I50
J 0
(-5775 2575);
DISPLAY 0.680851 (-5775 2575);
DISPLAY INVISIBLE (-5775 2575);
FORCEADD Q_RES..2
(-7875 4875);
FORCEPROP 1 LAST LOCATION R787
J 0
(-7830 5000);
DISPLAY 0.787234 (-7830 5000);
FORCEPROP 0 LAST $SEC 1
J 0
(-7825 5050);
DISPLAY 0.680851 (-7825 5050);
PAINT MONO (-7825 5050);
DISPLAY INVISIBLE (-7825 5050);
FORCEPROP 0 LAST CDS_SEC 1
J 0
(-7825 5050);
DISPLAY 0.680851 (-7825 5050);
DISPLAY INVISIBLE (-7825 5050);
FORCEPROP 1 LASTPIN (-7875 4975) $PN 1
J 0
(-7870 4937);
DISPLAY 0.787234 (-7870 4937);
PAINT MONO (-7870 4937);
FORCEPROP 1 LASTPIN (-7875 4775) $PN 2
J 0
(-7870 4785);
DISPLAY 0.787234 (-7870 4785);
PAINT MONO (-7870 4785);
FORCEPROP 1 LAST MATERIAL CHIP
J 0
(-7835 4800);
DISPLAY 0.787234 (-7835 4800);
FORCEPROP 1 LAST PACK_TYPE 0201LF
J 0
(-7835 4700);
DISPLAY 0.787234 (-7835 4700);
FORCEPROP 1 LAST VALUE 4.7K
J 0
(-7830 4950);
DISPLAY 0.787234 (-7830 4950);
FORCEPROP 1 LAST WATTAGE 1/20W
J 0
(-7835 4850);
DISPLAY 0.787234 (-7835 4850);
FORCEPROP 1 LAST TOLERANCE 5%
J 0
(-7830 4900);
DISPLAY 0.787234 (-7830 4900);
FORCEPROP 2 LAST CDS_LIB pure_quanta
J 0
(-7875 4875);
DISPLAY INVISIBLE (-7875 4875);
FORCEPROP 1 LAST PATH I51
J 0
(-7825 5050);
DISPLAY 0.978723 (-7825 5050);
PAINT WHITE (-7825 5050);
DISPLAY INVISIBLE (-7825 5050);
FORCEPROP 1 LAST PART_NUMBER CS24701JE04
J 0
(-7835 4750);
DISPLAY 0.978723 (-7835 4750);
DISPLAY INVISIBLE (-7835 4750);
FORCEADD Q_RES..2
(-7575 4875);
FORCEPROP 1 LAST LOCATION R791
J 0
(-7530 5000);
DISPLAY 0.787234 (-7530 5000);
FORCEPROP 0 LAST $SEC 1
J 0
(-7525 5050);
DISPLAY 0.680851 (-7525 5050);
PAINT MONO (-7525 5050);
DISPLAY INVISIBLE (-7525 5050);
FORCEPROP 0 LAST CDS_SEC 1
J 0
(-7525 5050);
DISPLAY 0.680851 (-7525 5050);
DISPLAY INVISIBLE (-7525 5050);
FORCEPROP 1 LASTPIN (-7575 4975) $PN 1
J 0
(-7570 4937);
DISPLAY 0.787234 (-7570 4937);
PAINT MONO (-7570 4937);
FORCEPROP 1 LASTPIN (-7575 4775) $PN 2
J 0
(-7570 4785);
DISPLAY 0.787234 (-7570 4785);
PAINT MONO (-7570 4785);
FORCEPROP 1 LAST MATERIAL CHIP
J 0
(-7535 4800);
DISPLAY 0.787234 (-7535 4800);
FORCEPROP 1 LAST WATTAGE 1/20W
J 0
(-7535 4850);
DISPLAY 0.787234 (-7535 4850);
FORCEPROP 1 LAST VALUE 4.7K
J 0
(-7530 4950);
DISPLAY 0.787234 (-7530 4950);
FORCEPROP 1 LAST TOLERANCE 5%
J 0
(-7530 4900);
DISPLAY 0.787234 (-7530 4900);
FORCEPROP 1 LAST PACK_TYPE 0201LF
J 0
(-7535 4700);
DISPLAY 0.787234 (-7535 4700);
FORCEPROP 2 LAST CDS_LIB pure_quanta
J 0
(-7575 4875);
DISPLAY INVISIBLE (-7575 4875);
FORCEPROP 1 LAST PATH I52
J 0
(-7525 5050);
DISPLAY 0.978723 (-7525 5050);
PAINT WHITE (-7525 5050);
DISPLAY INVISIBLE (-7525 5050);
FORCEPROP 1 LAST PART_NUMBER CS24701JE04
J 0
(-7535 4750);
DISPLAY 0.787234 (-7535 4750);
DISPLAY INVISIBLE (-7535 4750);
FORCEADD UNIVERSAL_GND..1
(-7275 4400);
FORCEPROP 3 LASTPIN (-7275 4450) SIG_NAME GND\g
J 0
(-7265 4460);
DISPLAY 0.659574 (-7265 4460);
PAINT MONO (-7265 4460);
DISPLAY INVISIBLE (-7265 4460);
FORCEPROP 2 LAST CDS_LIB pure_quanta_power
J 0
(-7275 4400);
DISPLAY INVISIBLE (-7275 4400);
FORCEPROP 1 LAST HDL_POWER GND
J 1
(-7250 4325);
DISPLAY 0.872340 (-7250 4325);
PAINT GREEN (-7250 4325);
DISPLAY INVISIBLE (-7250 4325);
FORCEPROP 1 LAST PATH I53
J 0
(-7200 4400);
DISPLAY 0.872340 (-7200 4400);
PAINT AQUA (-7200 4400);
DISPLAY INVISIBLE (-7200 4400);
FORCEADD Q_RES..2
(-7275 4850);
FORCEPROP 1 LAST LOCATION R792
J 0
(-7230 4975);
DISPLAY 0.787234 (-7230 4975);
FORCEPROP 0 LAST $SEC 1
J 0
(-7225 5025);
DISPLAY 0.680851 (-7225 5025);
PAINT MONO (-7225 5025);
DISPLAY INVISIBLE (-7225 5025);
FORCEPROP 0 LAST CDS_SEC 1
J 0
(-7225 5025);
DISPLAY 0.680851 (-7225 5025);
DISPLAY INVISIBLE (-7225 5025);
FORCEPROP 1 LASTPIN (-7275 4950) $PN 1
J 0
(-7270 4912);
DISPLAY 0.787234 (-7270 4912);
PAINT MONO (-7270 4912);
FORCEPROP 1 LASTPIN (-7275 4750) $PN 2
J 0
(-7270 4760);
DISPLAY 0.787234 (-7270 4760);
PAINT MONO (-7270 4760);
FORCEPROP 1 LAST TOLERANCE 5%
J 0
(-7230 4875);
DISPLAY 0.787234 (-7230 4875);
FORCEPROP 1 LAST VALUE 4.7K
J 0
(-7230 4925);
DISPLAY 0.787234 (-7230 4925);
FORCEPROP 1 LAST PACK_TYPE 0201LF
J 0
(-7235 4675);
DISPLAY 0.787234 (-7235 4675);
FORCEPROP 1 LAST MATERIAL CHIP
J 0
(-7235 4775);
DISPLAY 0.787234 (-7235 4775);
FORCEPROP 1 LAST WATTAGE 1/20W
J 0
(-7235 4825);
DISPLAY 0.787234 (-7235 4825);
FORCEPROP 2 LAST CDS_LIB pure_quanta
J 0
(-7275 4850);
DISPLAY INVISIBLE (-7275 4850);
FORCEPROP 1 LAST PATH I54
J 0
(-7225 5025);
DISPLAY 0.978723 (-7225 5025);
PAINT WHITE (-7225 5025);
DISPLAY INVISIBLE (-7225 5025);
FORCEPROP 1 LAST PART_NUMBER CS24701JE04
J 0
(-7235 4725);
DISPLAY 0.638298 (-7235 4725);
DISPLAY INVISIBLE (-7235 4725);
FORCEADD Q_RES..2
(-7875 5800);
FORCEPROP 1 LAST LOCATION R786
J 0
(-7830 5925);
DISPLAY 0.787234 (-7830 5925);
FORCEPROP 0 LAST $SEC 1
J 0
(-7825 5975);
DISPLAY 0.680851 (-7825 5975);
PAINT MONO (-7825 5975);
DISPLAY INVISIBLE (-7825 5975);
FORCEPROP 0 LAST CDS_SEC 1
J 0
(-7825 5975);
DISPLAY 0.680851 (-7825 5975);
DISPLAY INVISIBLE (-7825 5975);
FORCEPROP 1 LASTPIN (-7875 5900) $PN 1
J 0
(-7870 5862);
DISPLAY 0.787234 (-7870 5862);
PAINT MONO (-7870 5862);
FORCEPROP 1 LASTPIN (-7875 5700) $PN 2
J 0
(-7870 5710);
DISPLAY 0.787234 (-7870 5710);
PAINT MONO (-7870 5710);
FORCEPROP 1 LAST MATERIAL EMPTY
J 0
(-7835 5725);
DISPLAY 0.787234 (-7835 5725);
FORCEPROP 1 LAST PACK_TYPE 0201LF
J 0
(-7825 5650);
DISPLAY 0.787234 (-7825 5650);
FORCEPROP 1 LAST VALUE 4.7K
J 0
(-7830 5875);
DISPLAY 0.787234 (-7830 5875);
FORCEPROP 1 LAST TOLERANCE 5%
J 0
(-7830 5825);
DISPLAY 0.787234 (-7830 5825);
FORCEPROP 1 LAST WATTAGE 1/20W
J 0
(-7835 5775);
DISPLAY 0.787234 (-7835 5775);
FORCEPROP 2 LAST CDS_LIB pure_quanta
J 0
(-7875 5800);
DISPLAY INVISIBLE (-7875 5800);
FORCEPROP 1 LAST PATH I55
J 0
(-7825 5975);
DISPLAY 0.978723 (-7825 5975);
PAINT WHITE (-7825 5975);
DISPLAY INVISIBLE (-7825 5975);
FORCEPROP 1 LAST PART_NUMBER CS24701JE04
J 0
(-7835 5675);
DISPLAY 0.978723 (-7835 5675);
DISPLAY INVISIBLE (-7835 5675);
FORCEADD Q_RES..2
(-7575 5825);
FORCEPROP 1 LAST LOCATION R788
J 0
(-7530 5950);
DISPLAY 0.787234 (-7530 5950);
FORCEPROP 0 LAST $SEC 1
J 0
(-7525 6000);
DISPLAY 0.680851 (-7525 6000);
PAINT MONO (-7525 6000);
DISPLAY INVISIBLE (-7525 6000);
FORCEPROP 0 LAST CDS_SEC 1
J 0
(-7525 6000);
DISPLAY 0.680851 (-7525 6000);
DISPLAY INVISIBLE (-7525 6000);
FORCEPROP 1 LASTPIN (-7575 5925) $PN 1
J 0
(-7570 5887);
DISPLAY 0.787234 (-7570 5887);
PAINT MONO (-7570 5887);
FORCEPROP 1 LASTPIN (-7575 5725) $PN 2
J 0
(-7570 5735);
DISPLAY 0.787234 (-7570 5735);
PAINT MONO (-7570 5735);
FORCEPROP 1 LAST WATTAGE 1/20W
J 0
(-7535 5800);
DISPLAY 0.787234 (-7535 5800);
FORCEPROP 1 LAST PACK_TYPE 0201LF
J 0
(-7535 5650);
DISPLAY 0.787234 (-7535 5650);
FORCEPROP 1 LAST MATERIAL EMPTY
J 0
(-7535 5750);
DISPLAY 0.787234 (-7535 5750);
FORCEPROP 1 LAST TOLERANCE 5%
J 0
(-7530 5850);
DISPLAY 0.787234 (-7530 5850);
FORCEPROP 1 LAST VALUE 4.7K
J 0
(-7530 5900);
DISPLAY 0.787234 (-7530 5900);
FORCEPROP 2 LAST CDS_LIB pure_quanta
J 0
(-7575 5825);
DISPLAY INVISIBLE (-7575 5825);
FORCEPROP 1 LAST PATH I56
J 0
(-7525 6000);
DISPLAY 0.978723 (-7525 6000);
PAINT WHITE (-7525 6000);
DISPLAY INVISIBLE (-7525 6000);
FORCEPROP 1 LAST PART_NUMBER CS24701JE04
J 0
(-7535 5700);
DISPLAY 0.787234 (-7535 5700);
DISPLAY INVISIBLE (-7535 5700);
FORCEADD Q_RES..2
(-7275 5850);
FORCEPROP 1 LAST LOCATION R759
J 0
(-7230 5975);
DISPLAY 0.787234 (-7230 5975);
FORCEPROP 0 LAST $SEC 1
J 0
(-7225 6025);
DISPLAY 0.680851 (-7225 6025);
PAINT MONO (-7225 6025);
DISPLAY INVISIBLE (-7225 6025);
FORCEPROP 0 LAST CDS_SEC 1
J 0
(-7225 6025);
DISPLAY 0.680851 (-7225 6025);
DISPLAY INVISIBLE (-7225 6025);
FORCEPROP 1 LASTPIN (-7275 5950) $PN 1
J 0
(-7270 5912);
DISPLAY 0.787234 (-7270 5912);
PAINT MONO (-7270 5912);
FORCEPROP 1 LASTPIN (-7275 5750) $PN 2
J 0
(-7270 5760);
DISPLAY 0.787234 (-7270 5760);
PAINT MONO (-7270 5760);
FORCEPROP 1 LAST WATTAGE 1/20W
J 0
(-7235 5825);
DISPLAY 0.787234 (-7235 5825);
FORCEPROP 1 LAST VALUE 4.7K
J 0
(-7230 5925);
DISPLAY 0.787234 (-7230 5925);
FORCEPROP 1 LAST TOLERANCE 5%
J 0
(-7230 5875);
DISPLAY 0.787234 (-7230 5875);
FORCEPROP 1 LAST PACK_TYPE 0201LF
J 0
(-7225 5675);
DISPLAY 0.787234 (-7225 5675);
FORCEPROP 1 LAST MATERIAL EMPTY
J 0
(-7235 5775);
DISPLAY 0.787234 (-7235 5775);
FORCEPROP 2 LAST CDS_LIB pure_quanta
J 0
(-7275 5850);
DISPLAY INVISIBLE (-7275 5850);
FORCEPROP 1 LAST PATH I57
J 0
(-7225 6025);
DISPLAY 0.978723 (-7225 6025);
PAINT WHITE (-7225 6025);
DISPLAY INVISIBLE (-7225 6025);
FORCEPROP 1 LAST PART_NUMBER CS24701JE04
J 0
(-7225 5725);
DISPLAY 0.638298 (-7225 5725);
DISPLAY INVISIBLE (-7225 5725);
FORCEADD OFFPAGE..5
R 2
(-6225 5250);
FORCEPROP 2 LAST $XR0 332 
J 0
(-6036 5250);
DISPLAY 0.638298 (-6036 5250);
PAINT MONO (-6036 5250);
FORCEPROP 2 LAST CDS_LIB standard
J 0
(-6225 5250);
DISPLAY INVISIBLE (-6225 5250);
FORCEPROP 1 LAST OFFPAGE TRUE
J 2
(-6550 5125);
DISPLAY 0.872340 (-6550 5125);
PAINT GREEN (-6550 5125);
DISPLAY INVISIBLE (-6550 5125);
FORCEPROP 1 LAST COMMENT_BODY TRUE
J 2
(-6325 5175);
DISPLAY 0.872340 (-6325 5175);
PAINT GREEN (-6325 5175);
DISPLAY INVISIBLE (-6325 5175);
FORCEPROP 2 LAST PATH I58
J 0
(-6050 5325);
DISPLAY 0.680851 (-6050 5325);
DISPLAY INVISIBLE (-6050 5325);
FORCEADD OFFPAGE..5
R 2
(-6225 5325);
FORCEPROP 2 LAST $XR0 332 
J 0
(-6036 5325);
DISPLAY 0.638298 (-6036 5325);
PAINT MONO (-6036 5325);
FORCEPROP 2 LAST CDS_LIB standard
J 0
(-6225 5325);
DISPLAY INVISIBLE (-6225 5325);
FORCEPROP 1 LAST OFFPAGE TRUE
J 2
(-6550 5200);
DISPLAY 0.872340 (-6550 5200);
PAINT GREEN (-6550 5200);
DISPLAY INVISIBLE (-6550 5200);
FORCEPROP 1 LAST COMMENT_BODY TRUE
J 2
(-6325 5250);
DISPLAY 0.872340 (-6325 5250);
PAINT GREEN (-6325 5250);
DISPLAY INVISIBLE (-6325 5250);
FORCEPROP 2 LAST PATH I59
J 0
(-6025 5375);
DISPLAY 0.680851 (-6025 5375);
DISPLAY INVISIBLE (-6025 5375);
FORCEADD OFFPAGE..5
R 2
(-6225 5375);
FORCEPROP 2 LAST $XR0 332 
J 0
(-6036 5375);
DISPLAY 0.638298 (-6036 5375);
PAINT MONO (-6036 5375);
FORCEPROP 2 LAST CDS_LIB standard
J 0
(-6225 5375);
DISPLAY INVISIBLE (-6225 5375);
FORCEPROP 1 LAST OFFPAGE TRUE
J 2
(-6550 5250);
DISPLAY 0.872340 (-6550 5250);
PAINT GREEN (-6550 5250);
DISPLAY INVISIBLE (-6550 5250);
FORCEPROP 1 LAST COMMENT_BODY TRUE
J 2
(-6325 5300);
DISPLAY 0.872340 (-6325 5300);
PAINT GREEN (-6325 5300);
DISPLAY INVISIBLE (-6325 5300);
FORCEPROP 2 LAST PATH I60
J 0
(-6025 5425);
DISPLAY 0.680851 (-6025 5425);
DISPLAY INVISIBLE (-6025 5425);
FORCEADD OFFPAGE..5
R 2
(-6225 5425);
FORCEPROP 2 LAST $XR0 332 
J 0
(-6036 5425);
DISPLAY 0.638298 (-6036 5425);
PAINT MONO (-6036 5425);
FORCEPROP 2 LAST CDS_LIB standard
J 0
(-6225 5425);
DISPLAY INVISIBLE (-6225 5425);
FORCEPROP 1 LAST OFFPAGE TRUE
J 2
(-6550 5300);
DISPLAY 0.872340 (-6550 5300);
PAINT GREEN (-6550 5300);
DISPLAY INVISIBLE (-6550 5300);
FORCEPROP 1 LAST COMMENT_BODY TRUE
J 2
(-6325 5350);
DISPLAY 0.872340 (-6325 5350);
PAINT GREEN (-6325 5350);
DISPLAY INVISIBLE (-6325 5350);
FORCEPROP 2 LAST PATH I61
J 0
(-6025 5475);
DISPLAY 0.680851 (-6025 5475);
DISPLAY INVISIBLE (-6025 5475);
FORCEADD OFFPAGE..5
R 2
(-6225 5475);
FORCEPROP 2 LAST $XR0 332 
J 0
(-6036 5475);
DISPLAY 0.638298 (-6036 5475);
PAINT MONO (-6036 5475);
FORCEPROP 2 LAST CDS_LIB standard
J 0
(-6225 5475);
DISPLAY INVISIBLE (-6225 5475);
FORCEPROP 1 LAST OFFPAGE TRUE
J 2
(-6550 5350);
DISPLAY 0.872340 (-6550 5350);
PAINT GREEN (-6550 5350);
DISPLAY INVISIBLE (-6550 5350);
FORCEPROP 1 LAST COMMENT_BODY TRUE
J 2
(-6325 5400);
DISPLAY 0.872340 (-6325 5400);
PAINT GREEN (-6325 5400);
DISPLAY INVISIBLE (-6325 5400);
FORCEPROP 2 LAST PATH I62
J 0
(-6025 5525);
DISPLAY 0.680851 (-6025 5525);
DISPLAY INVISIBLE (-6025 5525);
FORCEADD OFFPAGE..5
R 2
(-6225 5550);
FORCEPROP 2 LAST $XR0 332 
J 0
(-6036 5550);
DISPLAY 0.638298 (-6036 5550);
PAINT MONO (-6036 5550);
FORCEPROP 2 LAST CDS_LIB standard
J 0
(-6225 5550);
DISPLAY INVISIBLE (-6225 5550);
FORCEPROP 1 LAST OFFPAGE TRUE
J 2
(-6550 5425);
DISPLAY 0.872340 (-6550 5425);
PAINT GREEN (-6550 5425);
DISPLAY INVISIBLE (-6550 5425);
FORCEPROP 1 LAST COMMENT_BODY TRUE
J 2
(-6325 5475);
DISPLAY 0.872340 (-6325 5475);
PAINT GREEN (-6325 5475);
DISPLAY INVISIBLE (-6325 5475);
FORCEPROP 2 LAST PATH I63
J 0
(-6025 5600);
DISPLAY 0.680851 (-6025 5600);
DISPLAY INVISIBLE (-6025 5600);
FORCEADD UNIVERSAL_GND..1
(-4875 5050);
FORCEPROP 3 LASTPIN (-4875 5100) SIG_NAME GND\g
J 0
(-4865 5110);
DISPLAY 0.659574 (-4865 5110);
PAINT MONO (-4865 5110);
DISPLAY INVISIBLE (-4865 5110);
FORCEPROP 2 LAST CDS_LIB pure_quanta_power
J 0
(-4875 5050);
DISPLAY INVISIBLE (-4875 5050);
FORCEPROP 1 LAST HDL_POWER GND
J 1
(-4850 4975);
DISPLAY 0.872340 (-4850 4975);
PAINT GREEN (-4850 4975);
DISPLAY INVISIBLE (-4850 4975);
FORCEPROP 1 LAST PATH I64
J 0
(-4800 5050);
DISPLAY 0.872340 (-4800 5050);
PAINT AQUA (-4800 5050);
DISPLAY INVISIBLE (-4800 5050);
FORCEADD Q_RES..2
(-4875 5400);
FORCEPROP 1 LAST LOCATION R794
J 0
(-4830 5525);
DISPLAY 0.787234 (-4830 5525);
FORCEPROP 0 LAST $SEC 1
J 0
(-4825 5575);
DISPLAY 0.680851 (-4825 5575);
PAINT MONO (-4825 5575);
DISPLAY INVISIBLE (-4825 5575);
FORCEPROP 0 LAST CDS_SEC 1
J 0
(-4825 5575);
DISPLAY 0.680851 (-4825 5575);
DISPLAY INVISIBLE (-4825 5575);
FORCEPROP 1 LASTPIN (-4875 5500) $PN 1
J 0
(-4870 5462);
DISPLAY 0.787234 (-4870 5462);
PAINT MONO (-4870 5462);
FORCEPROP 1 LASTPIN (-4875 5300) $PN 2
J 0
(-4870 5310);
DISPLAY 0.787234 (-4870 5310);
PAINT MONO (-4870 5310);
FORCEPROP 1 LAST WATTAGE 1/20W
J 0
(-4835 5375);
DISPLAY 0.787234 (-4835 5375);
FORCEPROP 1 LAST PACK_TYPE 0201LF
J 0
(-4835 5225);
DISPLAY 0.787234 (-4835 5225);
FORCEPROP 1 LAST VALUE 4.7K
J 0
(-4830 5475);
DISPLAY 0.787234 (-4830 5475);
FORCEPROP 1 LAST TOLERANCE 5%
J 0
(-4830 5425);
DISPLAY 0.787234 (-4830 5425);
FORCEPROP 1 LAST MATERIAL EMPTY
J 0
(-4835 5325);
DISPLAY 0.787234 (-4835 5325);
FORCEPROP 2 LAST CDS_LIB pure_quanta
J 0
(-4875 5400);
DISPLAY INVISIBLE (-4875 5400);
FORCEPROP 1 LAST PATH I65
J 0
(-4825 5575);
DISPLAY 0.978723 (-4825 5575);
PAINT WHITE (-4825 5575);
DISPLAY INVISIBLE (-4825 5575);
FORCEPROP 1 LAST PART_NUMBER CS24701JE04
J 0
(-4835 5275);
DISPLAY 0.787234 (-4835 5275);
DISPLAY INVISIBLE (-4835 5275);
FORCEADD Q_RES..2
(-4875 5925);
FORCEPROP 1 LAST LOCATION R793
J 0
(-4830 6050);
DISPLAY 0.787234 (-4830 6050);
FORCEPROP 0 LAST $SEC 1
J 0
(-4825 6100);
DISPLAY 0.680851 (-4825 6100);
PAINT MONO (-4825 6100);
DISPLAY INVISIBLE (-4825 6100);
FORCEPROP 0 LAST CDS_SEC 1
J 0
(-4825 6100);
DISPLAY 0.680851 (-4825 6100);
DISPLAY INVISIBLE (-4825 6100);
FORCEPROP 1 LASTPIN (-4875 6025) $PN 1
J 0
(-4870 5987);
DISPLAY 0.787234 (-4870 5987);
PAINT MONO (-4870 5987);
FORCEPROP 1 LASTPIN (-4875 5825) $PN 2
J 0
(-4870 5835);
DISPLAY 0.787234 (-4870 5835);
PAINT MONO (-4870 5835);
FORCEPROP 1 LAST PACK_TYPE 0201LF
J 0
(-4835 5750);
DISPLAY 0.787234 (-4835 5750);
FORCEPROP 1 LAST MATERIAL CHIP
J 0
(-4835 5850);
DISPLAY 0.787234 (-4835 5850);
FORCEPROP 1 LAST WATTAGE 1/20W
J 0
(-4835 5900);
DISPLAY 0.787234 (-4835 5900);
FORCEPROP 1 LAST TOLERANCE 5%
J 0
(-4830 5950);
DISPLAY 0.787234 (-4830 5950);
FORCEPROP 1 LAST VALUE 4.7K
J 0
(-4830 6000);
DISPLAY 0.787234 (-4830 6000);
FORCEPROP 2 LAST CDS_LIB pure_quanta
J 0
(-4875 5925);
DISPLAY INVISIBLE (-4875 5925);
FORCEPROP 1 LAST PATH I66
J 0
(-4825 6100);
DISPLAY 0.978723 (-4825 6100);
PAINT WHITE (-4825 6100);
DISPLAY INVISIBLE (-4825 6100);
FORCEPROP 1 LAST PART_NUMBER CS24701JE04
J 0
(-4835 5800);
DISPLAY 0.787234 (-4835 5800);
DISPLAY INVISIBLE (-4835 5800);
FORCEADD OFFPAGE..5
R 2
(-4000 5650);
FORCEPROP 2 LAST $XR0 332 
J 0
(-3811 5650);
DISPLAY 0.638298 (-3811 5650);
PAINT MONO (-3811 5650);
FORCEPROP 2 LAST CDS_LIB standard
J 0
(-4000 5650);
DISPLAY INVISIBLE (-4000 5650);
FORCEPROP 1 LAST OFFPAGE TRUE
J 2
(-4325 5525);
DISPLAY 0.872340 (-4325 5525);
PAINT GREEN (-4325 5525);
DISPLAY INVISIBLE (-4325 5525);
FORCEPROP 1 LAST COMMENT_BODY TRUE
J 2
(-4100 5575);
DISPLAY 0.872340 (-4100 5575);
PAINT GREEN (-4100 5575);
DISPLAY INVISIBLE (-4100 5575);
FORCEPROP 2 LAST PATH I67
J 0
(-3800 5700);
DISPLAY 0.680851 (-3800 5700);
DISPLAY INVISIBLE (-3800 5700);
FORCEADD P1V0..1
(-4875 6250);
FORCEPROP 3 LASTPIN (-4875 6200) SIG_NAME P1V8_CPU1_RT_1D\g
J 0
(-4865 6210);
DISPLAY 0.659574 (-4865 6210);
PAINT MONO (-4865 6210);
DISPLAY INVISIBLE (-4865 6210);
FORCEPROP 1 LAST HDL_POWER P1V8_CPU1_RT_1D
J 1
(-4875 6300);
DISPLAY 0.489362 (-4875 6300);
PAINT SKYBLUE (-4875 6300);
FORCEPROP 2 LAST CDS_LIB pure_quanta_power
J 0
(-4875 6250);
DISPLAY INVISIBLE (-4875 6250);
FORCEPROP 1 LAST PATH I68
J 0
(-4825 6275);
DISPLAY 0.872340 (-4825 6275);
PAINT AQUA (-4825 6275);
DISPLAY INVISIBLE (-4825 6275);
FORCEADD UNIVERSAL_GND..1
R 1
(-3150 1550);
FORCEPROP 3 LASTPIN (-3200 1550) SIG_NAME GND\g
J 0
(-3190 1560);
DISPLAY 0.659574 (-3190 1560);
PAINT MONO (-3190 1560);
DISPLAY INVISIBLE (-3190 1560);
FORCEPROP 2 LAST CDS_LIB pure_quanta_power
J 0
(-3150 1550);
DISPLAY INVISIBLE (-3150 1550);
FORCEPROP 1 LAST HDL_POWER GND
R 1
J 1
(-3075 1575);
DISPLAY 0.872340 (-3075 1575);
PAINT GREEN (-3075 1575);
DISPLAY INVISIBLE (-3075 1575);
FORCEPROP 1 LAST PATH I69
R 1
J 0
(-3150 1625);
DISPLAY 0.872340 (-3150 1625);
PAINT AQUA (-3150 1625);
DISPLAY INVISIBLE (-3150 1625);
FORCEADD Q_RES..1
(-2425 2050);
FORCEPROP 1 LAST LOCATION R731
J 0
(-2700 2050);
DISPLAY 0.978723 (-2700 2050);
FORCEPROP 2 LAST SEC 1
J 0
(-2475 2250);
DISPLAY 0.680851 (-2475 2250);
PAINT MONO (-2475 2250);
DISPLAY INVISIBLE (-2475 2250);
FORCEPROP 1 LASTPIN (-2525 2050) $PN 1
J 0
(-2513 2062);
DISPLAY 0.787234 (-2513 2062);
PAINT MONO (-2513 2062);
FORCEPROP 1 LASTPIN (-2325 2050) $PN 2
J 0
(-2363 2062);
DISPLAY 0.787234 (-2363 2062);
PAINT MONO (-2363 2062);
FORCEPROP 1 LAST VALUE 0
J 2
(-2225 2050);
DISPLAY 0.787234 (-2225 2050);
FORCEPROP 1 LAST PACK_TYPE 0201LF
J 0
(-2125 2050);
DISPLAY 0.787234 (-2125 2050);
FORCEPROP 2 LAST CDS_LIB pure_quanta
J 0
(-2425 2050);
DISPLAY INVISIBLE (-2425 2050);
FORCEPROP 2 LAST SEC_TYPE 0201LF
J 0
(-2475 2250);
DISPLAY 0.680851 (-2475 2250);
DISPLAY INVISIBLE (-2475 2250);
FORCEPROP 1 LAST MATERIAL CHIP
J 0
(-2600 2125);
DISPLAY 0.787234 (-2600 2125);
DISPLAY INVISIBLE (-2600 2125);
FORCEPROP 1 LAST TOLERANCE 5%
J 0
(-2600 2175);
DISPLAY 0.787234 (-2600 2175);
DISPLAY INVISIBLE (-2600 2175);
FORCEPROP 1 LAST WATTAGE 1/20W
J 2
(-2625 2125);
DISPLAY 0.787234 (-2625 2125);
DISPLAY INVISIBLE (-2625 2125);
FORCEPROP 1 LAST PATH I70
J 0
(-2475 2200);
DISPLAY 0.978723 (-2475 2200);
PAINT WHITE (-2475 2200);
DISPLAY INVISIBLE (-2475 2200);
FORCEPROP 1 LAST PART_NUMBER CS00001JE10
J 0
(-2475 2175);
DISPLAY 0.808511 (-2475 2175);
DISPLAY INVISIBLE (-2475 2175);
FORCEADD Q_RES..1
(-2425 1950);
FORCEPROP 1 LAST LOCATION R732
J 0
(-2700 1950);
DISPLAY 0.978723 (-2700 1950);
FORCEPROP 0 LAST $SEC 1
J 0
(-2125 2000);
DISPLAY 0.680851 (-2125 2000);
PAINT MONO (-2125 2000);
DISPLAY INVISIBLE (-2125 2000);
FORCEPROP 0 LAST CDS_SEC 1
J 0
(-2125 2000);
DISPLAY 0.680851 (-2125 2000);
DISPLAY INVISIBLE (-2125 2000);
FORCEPROP 1 LASTPIN (-2525 1950) $PN 1
J 0
(-2513 1962);
DISPLAY 0.787234 (-2513 1962);
PAINT MONO (-2513 1962);
FORCEPROP 1 LASTPIN (-2325 1950) $PN 2
J 0
(-2363 1962);
DISPLAY 0.787234 (-2363 1962);
PAINT MONO (-2363 1962);
FORCEPROP 1 LAST PACK_TYPE 0201LF
J 0
(-2125 1950);
DISPLAY 0.787234 (-2125 1950);
FORCEPROP 1 LAST VALUE 0
J 2
(-2225 1950);
DISPLAY 0.787234 (-2225 1950);
FORCEPROP 1 LAST WATTAGE 1/20W
J 2
(-2625 2025);
DISPLAY 0.787234 (-2625 2025);
DISPLAY INVISIBLE (-2625 2025);
FORCEPROP 1 LAST TOLERANCE 5%
J 0
(-2600 2075);
DISPLAY 0.787234 (-2600 2075);
DISPLAY INVISIBLE (-2600 2075);
FORCEPROP 1 LAST MATERIAL CHIP
J 0
(-2600 2025);
DISPLAY 0.787234 (-2600 2025);
DISPLAY INVISIBLE (-2600 2025);
FORCEPROP 2 LAST CDS_LIB pure_quanta
J 0
(-2425 1950);
DISPLAY INVISIBLE (-2425 1950);
FORCEPROP 1 LAST PATH I71
J 0
(-2475 2100);
DISPLAY 0.978723 (-2475 2100);
PAINT WHITE (-2475 2100);
DISPLAY INVISIBLE (-2475 2100);
FORCEPROP 1 LAST PART_NUMBER CS00001JE10
J 0
(-2475 2075);
DISPLAY 0.808511 (-2475 2075);
DISPLAY INVISIBLE (-2475 2075);
FORCEADD OFFPAGE..1
R 2
(-2225 2450);
FORCEPROP 2 LAST $XR0 332 
J 0
(-2039 2450);
DISPLAY 0.638298 (-2039 2450);
PAINT MONO (-2039 2450);
FORCEPROP 2 LAST CDS_LIB standard
J 0
(-2225 2450);
DISPLAY INVISIBLE (-2225 2450);
FORCEPROP 1 LAST OFFPAGE TRUE
J 2
(-2550 2325);
DISPLAY 0.872340 (-2550 2325);
DISPLAY INVISIBLE (-2550 2325);
FORCEPROP 1 LAST COMMENT_BODY TRUE
J 2
(-2350 2350);
DISPLAY 0.872340 (-2350 2350);
PAINT GREEN (-2350 2350);
DISPLAY INVISIBLE (-2350 2350);
FORCEPROP 2 LAST PATH I73
J 0
(-2050 2525);
DISPLAY 0.680851 (-2050 2525);
DISPLAY INVISIBLE (-2050 2525);
FORCEADD OFFPAGE..1
R 2
(-2250 2650);
FORCEPROP 2 LAST $XR0 332 
J 0
(-2064 2650);
DISPLAY 0.638298 (-2064 2650);
PAINT MONO (-2064 2650);
FORCEPROP 2 LAST CDS_LIB standard
J 2
(-2250 2650);
DISPLAY INVISIBLE (-2250 2650);
FORCEPROP 1 LAST OFFPAGE TRUE
J 2
(-2575 2525);
DISPLAY 0.872340 (-2575 2525);
DISPLAY INVISIBLE (-2575 2525);
FORCEPROP 1 LAST COMMENT_BODY TRUE
J 2
(-2375 2550);
DISPLAY 0.872340 (-2375 2550);
PAINT GREEN (-2375 2550);
DISPLAY INVISIBLE (-2375 2550);
FORCEPROP 2 LAST PATH I74
J 0
(-2050 2700);
DISPLAY 0.680851 (-2050 2700);
DISPLAY INVISIBLE (-2050 2700);
FORCEADD OFFPAGE..1
R 2
(-2325 2950);
FORCEPROP 2 LAST $XR0 332 
J 0
(-2139 2950);
DISPLAY 0.638298 (-2139 2950);
PAINT MONO (-2139 2950);
FORCEPROP 2 LAST CDS_LIB standard
J 0
(-2325 2950);
DISPLAY INVISIBLE (-2325 2950);
FORCEPROP 1 LAST OFFPAGE TRUE
J 2
(-2650 2825);
DISPLAY 0.872340 (-2650 2825);
DISPLAY INVISIBLE (-2650 2825);
FORCEPROP 1 LAST COMMENT_BODY TRUE
J 2
(-2450 2850);
DISPLAY 0.872340 (-2450 2850);
PAINT GREEN (-2450 2850);
DISPLAY INVISIBLE (-2450 2850);
FORCEPROP 2 LAST PATH I76
J 0
(-2150 3025);
DISPLAY 0.680851 (-2150 3025);
DISPLAY INVISIBLE (-2150 3025);
FORCEADD OFFPAGE..1
R 2
(-900 1950);
FORCEPROP 2 LAST $XR1 332 
J 0
(-624 1950);
DISPLAY 0.638298 (-624 1950);
PAINT MONO (-624 1950);
FORCEPROP 2 LAST $XR0 81 
J 0
(-714 1950);
DISPLAY 0.638298 (-714 1950);
PAINT MONO (-714 1950);
FORCEPROP 2 LAST CDS_LIB standard
J 0
(-900 1950);
DISPLAY INVISIBLE (-900 1950);
FORCEPROP 1 LAST OFFPAGE TRUE
J 2
(-1225 1825);
DISPLAY 0.872340 (-1225 1825);
DISPLAY INVISIBLE (-1225 1825);
FORCEPROP 1 LAST COMMENT_BODY TRUE
J 2
(-1025 1850);
DISPLAY 0.872340 (-1025 1850);
PAINT GREEN (-1025 1850);
DISPLAY INVISIBLE (-1025 1850);
FORCEPROP 2 LAST PATH I77
J 0
(-725 2025);
DISPLAY 0.680851 (-725 2025);
DISPLAY INVISIBLE (-725 2025);
FORCEADD OFFPAGE..1
R 2
(-900 2050);
FORCEPROP 2 LAST $XR1 332 
J 0
(-624 2050);
DISPLAY 0.638298 (-624 2050);
PAINT MONO (-624 2050);
FORCEPROP 2 LAST $XR0 81 
J 0
(-714 2050);
DISPLAY 0.638298 (-714 2050);
PAINT MONO (-714 2050);
FORCEPROP 2 LAST CDS_LIB standard
J 0
(-900 2050);
DISPLAY INVISIBLE (-900 2050);
FORCEPROP 1 LAST OFFPAGE TRUE
J 2
(-1225 1925);
DISPLAY 0.872340 (-1225 1925);
DISPLAY INVISIBLE (-1225 1925);
FORCEPROP 1 LAST COMMENT_BODY TRUE
J 2
(-1025 1950);
DISPLAY 0.872340 (-1025 1950);
PAINT GREEN (-1025 1950);
DISPLAY INVISIBLE (-1025 1950);
FORCEPROP 2 LAST PATH I78
J 0
(-725 2125);
DISPLAY 0.680851 (-725 2125);
DISPLAY INVISIBLE (-725 2125);
FORCEADD GND..1
(-1325 4700);
FORCEPROP 3 LASTPIN (-1325 4750) SIG_NAME GND\g
J 0
(-1315 4760);
DISPLAY 0.659574 (-1315 4760);
PAINT MONO (-1315 4760);
DISPLAY INVISIBLE (-1315 4760);
FORCEPROP 2 LAST BOM_COST MEM
J 0
(-1425 4775);
DISPLAY 0.808511 (-1425 4775);
DISPLAY INVISIBLE (-1425 4775);
FORCEPROP 1 LAST SIZE 1B
J 0
(-1250 4650);
DISPLAY 0.851064 (-1250 4650);
PAINT GREEN (-1250 4650);
DISPLAY INVISIBLE (-1250 4650);
FORCEPROP 2 LAST CDS_LIB pure_quanta_power
J 0
(-1325 4700);
DISPLAY INVISIBLE (-1325 4700);
FORCEPROP 1 LAST HDL_POWER GND
J 0
(-1325 4850);
DISPLAY 0.851064 (-1325 4850);
PAINT GREEN (-1325 4850);
DISPLAY INVISIBLE (-1325 4850);
FORCEPROP 1 LAST PATH I87
J 0
(-1250 4700);
DISPLAY 0.872340 (-1250 4700);
PAINT AQUA (-1250 4700);
DISPLAY INVISIBLE (-1250 4700);
FORCEADD GND..1
(-1150 4725);
FORCEPROP 3 LASTPIN (-1150 4775) SIG_NAME GND\g
J 0
(-1140 4785);
DISPLAY 0.659574 (-1140 4785);
PAINT MONO (-1140 4785);
DISPLAY INVISIBLE (-1140 4785);
FORCEPROP 2 LAST CDS_LIB pure_quanta_power
J 0
(-1150 4725);
DISPLAY INVISIBLE (-1150 4725);
FORCEPROP 2 LAST BOM_COST MEM
J 0
(-1250 4800);
DISPLAY 0.808511 (-1250 4800);
DISPLAY INVISIBLE (-1250 4800);
FORCEPROP 1 LAST SIZE 1B
J 0
(-1075 4675);
DISPLAY 0.851064 (-1075 4675);
PAINT GREEN (-1075 4675);
DISPLAY INVISIBLE (-1075 4675);
FORCEPROP 1 LAST HDL_POWER GND
J 0
(-1150 4875);
DISPLAY 0.851064 (-1150 4875);
PAINT GREEN (-1150 4875);
DISPLAY INVISIBLE (-1150 4875);
FORCEPROP 1 LAST PATH I88
J 0
(-1075 4725);
DISPLAY 0.872340 (-1075 4725);
PAINT AQUA (-1075 4725);
DISPLAY INVISIBLE (-1075 4725);
FORCEADD Q_RES..2
R 2
(-1325 5075);
FORCEPROP 1 LAST LOCATION R752
J 2
(-1370 5200);
DISPLAY 0.638298 (-1370 5200);
FORCEPROP 0 LAST $SEC 1
J 0
(-1350 5250);
DISPLAY 0.680851 (-1350 5250);
PAINT MONO (-1350 5250);
DISPLAY INVISIBLE (-1350 5250);
FORCEPROP 0 LAST CDS_SEC 1
J 0
(-1350 5250);
DISPLAY 0.680851 (-1350 5250);
DISPLAY INVISIBLE (-1350 5250);
FORCEPROP 1 LASTPIN (-1325 5175) $PN 1
J 2
(-1330 5137);
DISPLAY 0.787234 (-1330 5137);
PAINT MONO (-1330 5137);
FORCEPROP 1 LASTPIN (-1325 4975) $PN 2
J 2
(-1330 4985);
DISPLAY 0.787234 (-1330 4985);
PAINT MONO (-1330 4985);
FORCEPROP 1 LAST TOLERANCE 1%
J 2
(-1370 5100);
DISPLAY 0.638298 (-1370 5100);
FORCEPROP 1 LAST MATERIAL CHIP
J 2
(-1365 5000);
DISPLAY 0.638298 (-1365 5000);
FORCEPROP 1 LAST WATTAGE 1/20W
J 2
(-1365 5050);
DISPLAY 0.638298 (-1365 5050);
FORCEPROP 1 LAST PACK_TYPE 0201LF
J 2
(-1365 4900);
DISPLAY 0.638298 (-1365 4900);
FORCEPROP 1 LAST VALUE 10K
J 2
(-1370 5150);
DISPLAY 0.638298 (-1370 5150);
FORCEPROP 2 LAST CDS_LIB pure_quanta
J 2
(-1325 5075);
DISPLAY INVISIBLE (-1325 5075);
FORCEPROP 1 LAST PATH I92
J 2
(-1375 5250);
DISPLAY 0.978723 (-1375 5250);
PAINT WHITE (-1375 5250);
DISPLAY INVISIBLE (-1375 5250);
FORCEPROP 1 LAST PART_NUMBER CS31001FE17
J 2
(-1365 4950);
DISPLAY 0.638298 (-1365 4950);
DISPLAY INVISIBLE (-1365 4950);
FORCEADD Q_RES..2
(-1150 5075);
FORCEPROP 1 LAST LOCATION R749
J 0
(-1105 5200);
DISPLAY 0.638298 (-1105 5200);
FORCEPROP 0 LAST $SEC 1
J 0
(-1100 5250);
DISPLAY 0.680851 (-1100 5250);
PAINT MONO (-1100 5250);
DISPLAY INVISIBLE (-1100 5250);
FORCEPROP 0 LAST CDS_SEC 1
J 0
(-1100 5250);
DISPLAY 0.680851 (-1100 5250);
DISPLAY INVISIBLE (-1100 5250);
FORCEPROP 1 LASTPIN (-1150 5175) $PN 1
J 0
(-1145 5137);
DISPLAY 0.787234 (-1145 5137);
PAINT MONO (-1145 5137);
FORCEPROP 1 LASTPIN (-1150 4975) $PN 2
J 0
(-1145 4985);
DISPLAY 0.787234 (-1145 4985);
PAINT MONO (-1145 4985);
FORCEPROP 1 LAST PACK_TYPE 0201LF
J 0
(-1110 4900);
DISPLAY 0.638298 (-1110 4900);
FORCEPROP 1 LAST MATERIAL CHIP
J 0
(-1110 5000);
DISPLAY 0.638298 (-1110 5000);
FORCEPROP 1 LAST WATTAGE 1/20W
J 0
(-1110 5050);
DISPLAY 0.638298 (-1110 5050);
FORCEPROP 1 LAST VALUE 10K
J 0
(-1105 5150);
DISPLAY 0.638298 (-1105 5150);
FORCEPROP 1 LAST TOLERANCE 1%
J 0
(-1105 5100);
DISPLAY 0.638298 (-1105 5100);
FORCEPROP 2 LAST CDS_LIB pure_quanta
J 0
(-1150 5075);
DISPLAY INVISIBLE (-1150 5075);
FORCEPROP 1 LAST PATH I93
J 0
(-1100 5250);
DISPLAY 0.978723 (-1100 5250);
PAINT WHITE (-1100 5250);
DISPLAY INVISIBLE (-1100 5250);
FORCEPROP 1 LAST PART_NUMBER CS31001FE17
J 0
(-1110 4950);
DISPLAY 0.638298 (-1110 4950);
DISPLAY INVISIBLE (-1110 4950);
FORCEADD Q_RES..2
R 2
(-1325 5900);
FORCEPROP 1 LAST LOCATION R758
J 2
(-1370 6025);
DISPLAY 0.787234 (-1370 6025);
FORCEPROP 0 LAST $SEC 1
J 0
(-1350 6075);
DISPLAY 0.680851 (-1350 6075);
PAINT MONO (-1350 6075);
DISPLAY INVISIBLE (-1350 6075);
FORCEPROP 0 LAST CDS_SEC 1
J 0
(-1350 6075);
DISPLAY 0.680851 (-1350 6075);
DISPLAY INVISIBLE (-1350 6075);
FORCEPROP 1 LASTPIN (-1325 6000) $PN 1
J 2
(-1330 5962);
DISPLAY 0.787234 (-1330 5962);
PAINT MONO (-1330 5962);
FORCEPROP 1 LASTPIN (-1325 5800) $PN 2
J 2
(-1330 5810);
DISPLAY 0.787234 (-1330 5810);
PAINT MONO (-1330 5810);
FORCEPROP 1 LAST MATERIAL EMPTY
J 2
(-1365 5825);
DISPLAY 0.787234 (-1365 5825);
FORCEPROP 1 LAST TOLERANCE 5%
J 2
(-1370 5925);
DISPLAY 0.787234 (-1370 5925);
FORCEPROP 1 LAST VALUE 4.7K
J 2
(-1370 5975);
DISPLAY 0.787234 (-1370 5975);
FORCEPROP 1 LAST WATTAGE 1/20W
J 2
(-1365 5875);
DISPLAY 0.787234 (-1365 5875);
FORCEPROP 1 LAST PACK_TYPE 0201LF
J 2
(-1375 5750);
DISPLAY 0.787234 (-1375 5750);
FORCEPROP 2 LAST CDS_LIB pure_quanta
J 2
(-1325 5900);
DISPLAY INVISIBLE (-1325 5900);
FORCEPROP 1 LAST PATH I94
J 2
(-1375 6075);
DISPLAY 0.978723 (-1375 6075);
PAINT WHITE (-1375 6075);
DISPLAY INVISIBLE (-1375 6075);
FORCEPROP 1 LAST PART_NUMBER CS24701JE04
J 2
(-1365 5775);
DISPLAY 0.978723 (-1365 5775);
DISPLAY INVISIBLE (-1365 5775);
FORCEADD OFFPAGE..1
R 2
(-350 5450);
FORCEPROP 2 LAST $XR1 332 
J 0
(-164 5414);
DISPLAY 0.638298 (-164 5414);
PAINT MONO (-164 5414);
FORCEPROP 2 LAST $XR0 81 
J 0
(-164 5450);
DISPLAY 0.638298 (-164 5450);
PAINT MONO (-164 5450);
FORCEPROP 2 LAST CDS_LIB standard
J 0
(-350 5450);
DISPLAY INVISIBLE (-350 5450);
FORCEPROP 1 LAST OFFPAGE TRUE
J 2
(-675 5325);
DISPLAY 0.872340 (-675 5325);
PAINT GREEN (-675 5325);
DISPLAY INVISIBLE (-675 5325);
FORCEPROP 1 LAST COMMENT_BODY TRUE
J 2
(-475 5350);
DISPLAY 0.872340 (-475 5350);
PAINT GREEN (-475 5350);
DISPLAY INVISIBLE (-475 5350);
FORCEPROP 2 LAST PATH I95
J 0
(-175 5525);
DISPLAY 0.680851 (-175 5525);
DISPLAY INVISIBLE (-175 5525);
FORCEADD OFFPAGE..1
R 2
(-375 5300);
FORCEPROP 2 LAST $XR1 332 
J 0
(-99 5300);
DISPLAY 0.638298 (-99 5300);
PAINT MONO (-99 5300);
FORCEPROP 2 LAST $XR0 81 
J 0
(-189 5300);
DISPLAY 0.638298 (-189 5300);
PAINT MONO (-189 5300);
FORCEPROP 2 LAST CDS_LIB standard
J 0
(-375 5300);
DISPLAY INVISIBLE (-375 5300);
FORCEPROP 1 LAST OFFPAGE TRUE
J 2
(-700 5175);
DISPLAY 0.872340 (-700 5175);
PAINT GREEN (-700 5175);
DISPLAY INVISIBLE (-700 5175);
FORCEPROP 1 LAST COMMENT_BODY TRUE
J 2
(-500 5200);
DISPLAY 0.872340 (-500 5200);
PAINT GREEN (-500 5200);
DISPLAY INVISIBLE (-500 5200);
FORCEPROP 2 LAST PATH I96
J 0
(-200 5375);
DISPLAY 0.680851 (-200 5375);
DISPLAY INVISIBLE (-200 5375);
FORCEADD P1V0..1
(-1325 6150);
FORCEPROP 3 LASTPIN (-1325 6100) SIG_NAME P1V8_CPU1_RT_1D\g
J 0
(-1315 6110);
DISPLAY 0.659574 (-1315 6110);
PAINT MONO (-1315 6110);
DISPLAY INVISIBLE (-1315 6110);
FORCEPROP 1 LAST HDL_POWER P1V8_CPU1_RT_1D
J 1
(-1325 6200);
DISPLAY 0.489362 (-1325 6200);
PAINT SKYBLUE (-1325 6200);
FORCEPROP 2 LAST CDS_LIB pure_quanta_power
J 0
(-1325 6150);
DISPLAY INVISIBLE (-1325 6150);
FORCEPROP 1 LAST PATH I97
J 0
(-1275 6175);
DISPLAY 0.872340 (-1275 6175);
PAINT AQUA (-1275 6175);
DISPLAY INVISIBLE (-1275 6175);
FORCEADD DNS..1
(-1450 1350);
PAINT RED (-1450 1350);
FORCEPROP 2 LAST CDS_LIB mstr_misc
J 0
(-1450 1350);
DISPLAY INVISIBLE (-1450 1350);
FORCEPROP 1 LAST COMMENT_BODY TRUE
R 1
J 0
(-1375 1125);
DISPLAY 0.872340 (-1375 1125);
PAINT GREEN (-1375 1125);
DISPLAY INVISIBLE (-1375 1125);
FORCEADD DNS..1
(-1150 1300);
PAINT RED (-1150 1300);
FORCEPROP 2 LAST CDS_LIB mstr_misc
J 0
(-1150 1300);
DISPLAY INVISIBLE (-1150 1300);
FORCEPROP 1 LAST COMMENT_BODY TRUE
R 1
J 0
(-1075 1075);
DISPLAY 0.872340 (-1075 1075);
PAINT GREEN (-1075 1075);
DISPLAY INVISIBLE (-1075 1075);
FORCEADD DNS..1
(-575 1325);
PAINT RED (-575 1325);
FORCEPROP 2 LAST CDS_LIB mstr_misc
J 0
(-575 1325);
DISPLAY INVISIBLE (-575 1325);
FORCEPROP 1 LAST COMMENT_BODY TRUE
R 1
J 0
(-500 1100);
DISPLAY 0.872340 (-500 1100);
PAINT GREEN (-500 1100);
DISPLAY INVISIBLE (-500 1100);
FORCEADD DNS..1
(-850 1325);
PAINT RED (-850 1325);
FORCEPROP 2 LAST CDS_LIB mstr_misc
J 0
(-850 1325);
DISPLAY INVISIBLE (-850 1325);
FORCEPROP 1 LAST COMMENT_BODY TRUE
R 1
J 0
(-775 1100);
DISPLAY 0.872340 (-775 1100);
PAINT GREEN (-775 1100);
DISPLAY INVISIBLE (-775 1100);
FORCEADD DNS..1
(-8775 3950);
PAINT RED (-8775 3950);
FORCEPROP 2 LAST CDS_LIB mstr_misc
J 0
(-8775 3950);
DISPLAY INVISIBLE (-8775 3950);
FORCEPROP 1 LAST COMMENT_BODY TRUE
R 1
J 0
(-8700 3725);
DISPLAY 0.872340 (-8700 3725);
PAINT GREEN (-8700 3725);
DISPLAY INVISIBLE (-8700 3725);
FORCEADD DNS..1
(-6275 575);
PAINT RED (-6275 575);
FORCEPROP 2 LAST CDS_LIB mstr_misc
J 0
(-6275 575);
DISPLAY INVISIBLE (-6275 575);
FORCEPROP 1 LAST COMMENT_BODY TRUE
R 1
J 0
(-6200 350);
DISPLAY 0.872340 (-6200 350);
PAINT GREEN (-6200 350);
DISPLAY INVISIBLE (-6200 350);
FORCEADD DNS..1
(-5925 600);
PAINT RED (-5925 600);
FORCEPROP 2 LAST CDS_LIB mstr_misc
J 0
(-5925 600);
DISPLAY INVISIBLE (-5925 600);
FORCEPROP 1 LAST COMMENT_BODY TRUE
R 1
J 0
(-5850 375);
DISPLAY 0.872340 (-5850 375);
PAINT GREEN (-5850 375);
DISPLAY INVISIBLE (-5850 375);
FORCEADD DNS..1
(-8675 5825);
PAINT RED (-8675 5825);
FORCEPROP 2 LAST CDS_LIB mstr_misc
J 0
(-8675 5825);
DISPLAY INVISIBLE (-8675 5825);
FORCEPROP 1 LAST COMMENT_BODY TRUE
R 1
J 0
(-8600 5600);
DISPLAY 0.872340 (-8600 5600);
PAINT GREEN (-8600 5600);
DISPLAY INVISIBLE (-8600 5600);
FORCEADD DNS..1
(-8075 5850);
PAINT RED (-8075 5850);
FORCEPROP 2 LAST CDS_LIB mstr_misc
J 0
(-8075 5850);
DISPLAY INVISIBLE (-8075 5850);
FORCEPROP 1 LAST COMMENT_BODY TRUE
R 1
J 0
(-8000 5625);
DISPLAY 0.872340 (-8000 5625);
PAINT GREEN (-8000 5625);
DISPLAY INVISIBLE (-8000 5625);
FORCEADD DNS..1
(-7775 5825);
PAINT RED (-7775 5825);
FORCEPROP 2 LAST CDS_LIB mstr_misc
J 0
(-7775 5825);
DISPLAY INVISIBLE (-7775 5825);
FORCEPROP 1 LAST COMMENT_BODY TRUE
R 1
J 0
(-7700 5600);
DISPLAY 0.872340 (-7700 5600);
PAINT GREEN (-7700 5600);
DISPLAY INVISIBLE (-7700 5600);
FORCEADD DNS..1
(-7500 5875);
PAINT RED (-7500 5875);
FORCEPROP 2 LAST CDS_LIB mstr_misc
J 0
(-7500 5875);
DISPLAY INVISIBLE (-7500 5875);
FORCEPROP 1 LAST COMMENT_BODY TRUE
R 1
J 0
(-7425 5650);
DISPLAY 0.872340 (-7425 5650);
PAINT GREEN (-7425 5650);
DISPLAY INVISIBLE (-7425 5650);
FORCEADD DNS..1
(-7175 5825);
PAINT RED (-7175 5825);
FORCEPROP 2 LAST CDS_LIB mstr_misc
J 0
(-7175 5825);
DISPLAY INVISIBLE (-7175 5825);
FORCEPROP 1 LAST COMMENT_BODY TRUE
R 1
J 0
(-7100 5600);
DISPLAY 0.872340 (-7100 5600);
PAINT GREEN (-7100 5600);
DISPLAY INVISIBLE (-7100 5600);
FORCEADD DNS..1
(-4800 5350);
PAINT RED (-4800 5350);
FORCEPROP 2 LAST CDS_LIB mstr_misc
J 0
(-4800 5350);
DISPLAY INVISIBLE (-4800 5350);
FORCEPROP 1 LAST COMMENT_BODY TRUE
R 1
J 0
(-4725 5125);
DISPLAY 0.872340 (-4725 5125);
PAINT GREEN (-4725 5125);
DISPLAY INVISIBLE (-4725 5125);
FORCEADD DNS..1
(-1325 5925);
PAINT RED (-1325 5925);
FORCEPROP 2 LAST CDS_LIB mstr_misc
J 0
(-1325 5925);
DISPLAY INVISIBLE (-1325 5925);
FORCEPROP 1 LAST COMMENT_BODY TRUE
R 1
J 0
(-1250 5700);
DISPLAY 0.872340 (-1250 5700);
PAINT GREEN (-1250 5700);
DISPLAY INVISIBLE (-1250 5700);
FORCEADD QUANTA_TITLE_BLOCK_C..1
(0 0);
FORCEPROP 0 LAST CDS_CON_LAST_MODIFIED Thu Sep 14 16:13:04 2023
J 0
(-1885 15);
DISPLAY INVISIBLE (-1885 15);
FORCEPROP 1 LAST CUSTOM_TXT_CDS <CON_LAST_MODIFIED>
J 0
(-1885 15);
DISPLAY 0.978723 (-1885 15);
FORCEPROP 2 LAST CUSTOM_TXT_CDS <XR_PAGE_TITLE>
J 0
(-7890 5250);
DISPLAY 0.638298 (-7890 5250);
PAINT PINK (-7890 5250);
DISPLAY INVISIBLE (-7890 5250);
FORCEPROP 1 LAST CUSTOM_TXT_CDS <NAME_2>
J 0
(-3175 50);
FORCEPROP 1 LAST CUSTOM_TXT_CDS <NAME_1>
J 0
(-3175 175);
FORCEPROP 1 LAST CUSTOM_TXT_CDS <Q_NUMBER>
J 0
(-1403 103);
DISPLAY 1.212766 (-1403 103);
FORCEPROP 1 LAST CUSTOM_TXT_CDS <Q_PROJ>
J 0
(-2382 102);
DISPLAY 1.212766 (-2382 102);
FORCEPROP 1 LAST CUSTOM_TXT_CDS <Q_REV>
J 0
(-184 103);
DISPLAY 1.212766 (-184 103);
FORCEPROP 1 LAST CUSTOM_TXT_CDS <CON_PAGE_NUM> OF <CON_TOTAL_PAGES>
J 0
(-446 18);
DISPLAY 0.978723 (-446 18);
FORCEPROP 1 LAST Q_TITLE RETIMER_CPU1_P1(5)
J 0
(-9366 26);
DISPLAY 2.446809 (-9366 26);
PAINT GREEN (-9366 26);
FORCEPROP 2 LAST CDS_LIB pure_quanta
J 0
(0 0);
DISPLAY INVISIBLE (0 0);
FORCEPROP 1 LAST CDS_LMAN_SYM_OUTLINE -9475,6775,100,-125
J 0
(0 0);
DISPLAY 0.468085 (0 0);
PAINT GREEN (0 0);
DISPLAY INVISIBLE (0 0);
FORCEPROP 2 LAST PAGE_BORDER TRUE
J 0
(-7890 5250);
DISPLAY 0.638298 (-7890 5250);
PAINT PINK (-7890 5250);
DISPLAY INVISIBLE (-7890 5250);
FORCEPROP 2 LAST CDS_XR_PAGE_TITLE CR-332 : @T6G_MB_LIB.T6G(SCH_1):PAGE332
J 0
(-7890 5250);
DISPLAY 0.638298 (-7890 5250);
PAINT PINK (-7890 5250);
DISPLAY INVISIBLE (-7890 5250);
FORCEPROP 1 LAST Q_DEPT BU9
J 1
(-3763 49);
DISPLAY 1.957447 (-3763 49);
PAINT GREEN (-3763 49);
DISPLAY INVISIBLE (-3763 49);
FORCEPROP 1 LAST COMMENT_BODY TRUE
J 0
(12 -13);
DISPLAY 0.978723 (12 -13);
PAINT GREEN (12 -13);
DISPLAY INVISIBLE (12 -13);
FORCEADD DNS..1
(-2775 5950);
PAINT RED (-2775 5950);
FORCEPROP 2 LAST CDS_LIB mstr_misc
J 0
(-2775 5950);
DISPLAY INVISIBLE (-2775 5950);
FORCEPROP 1 LAST COMMENT_BODY TRUE
R 1
J 0
(-2700 5725);
DISPLAY 0.872340 (-2700 5725);
PAINT GREEN (-2700 5725);
DISPLAY INVISIBLE (-2700 5725);
FORCEADD DNS..1
(-3125 5975);
PAINT RED (-3125 5975);
FORCEPROP 2 LAST CDS_LIB mstr_misc
J 0
(-3125 5975);
DISPLAY INVISIBLE (-3125 5975);
FORCEPROP 1 LAST COMMENT_BODY TRUE
R 1
J 0
(-3050 5750);
DISPLAY 0.872340 (-3050 5750);
PAINT GREEN (-3050 5750);
DISPLAY INVISIBLE (-3050 5750);
FORCEADD DNS..1
(-3425 5150);
PAINT RED (-3425 5150);
FORCEPROP 2 LAST CDS_LIB mstr_misc
J 0
(-3425 5150);
DISPLAY INVISIBLE (-3425 5150);
FORCEPROP 1 LAST COMMENT_BODY TRUE
R 1
J 0
(-3350 4925);
DISPLAY 0.872340 (-3350 4925);
PAINT GREEN (-3350 4925);
DISPLAY INVISIBLE (-3350 4925);
FORCEADD DNS..1
(-1375 3700);
PAINT RED (-1375 3700);
FORCEPROP 2 LAST CDS_LIB mstr_misc
J 0
(-1375 3700);
DISPLAY INVISIBLE (-1375 3700);
FORCEPROP 1 LAST COMMENT_BODY TRUE
R 1
J 0
(-1300 3475);
DISPLAY 0.872340 (-1300 3475);
PAINT GREEN (-1300 3475);
DISPLAY INVISIBLE (-1300 3475);
WIRE 16 -1 (-2425 2150)(-1850 2150);
WIRE 16 -1 (-1450 3075)(-1450 2825);
WIRE 16 -1 (-1450 3800)(-1450 4050);
WIRE 16 -1 (-2450 3100)(-1850 3100);
WIRE 16 -1 (-650 575)(-650 425);
WIRE 16 -1 (-8825 3200)(-8825 3075);
WIRE 16 -1 (-8825 4075)(-8825 4250);
WIRE 16 -1 (-6150 475)(-6150 300);
WIRE 16 -1 (-6000 475)(-6000 300);
WIRE 16 -1 (-4875 5300)(-4875 5100);
WIRE 16 -1 (-4875 6025)(-4875 6200);
WIRE 16 -1 (-3625 1550)(-3200 1550);
WIRE 16 -1 (-1325 4975)(-1325 4750);
WIRE 16 -1 (-1150 4975)(-1150 4775);
WIRE 16 -1 (-1325 6100)(-1325 6000);
WIRE 16 -1 (-6275 1500)(-7450 1500);
FORCEPROP 2 LAST SIG_NAME SMB_RT_CPU1_P1_ROM_MUX_1D_SCL
J 0
(-7360 1510);
DISPLAY 0.680851 (-7360 1510);
PAINT SKYBLUE (-7360 1510);
WIRE 16 -1 (-4875 1500)(-6075 1500);
FORCEPROP 2 LAST SIG_NAME SMB_RT_CPU1_P1_ROM_MUX_1D_R_SCL
J 0
(-6010 1525);
DISPLAY 0.680851 (-6010 1525);
PAINT SKYBLUE (-6010 1525);
FORCEPROP 2 LASTPROP $XRERR UNIQUE?
J 0
(-6250 1525);
DISPLAY 0.638298 (-6250 1525);
PAINT MONO (-6250 1525);
DISPLAY INVISIBLE (-6250 1525);
WIRE 16 -1 (-6275 1400)(-7450 1400);
FORCEPROP 2 LAST SIG_NAME SMB_RT_CPU1_P1_ROM_MUX_1D_SDA
J 0
(-7385 1410);
DISPLAY 0.680851 (-7385 1410);
PAINT SKYBLUE (-7385 1410);
WIRE 16 -1 (-4875 1400)(-6075 1400);
FORCEPROP 2 LAST SIG_NAME SMB_RT_CPU1_P1_ROM_MUX_1D_R_SDA
J 0
(-6010 1425);
DISPLAY 0.680851 (-6010 1425);
PAINT SKYBLUE (-6010 1425);
FORCEPROP 2 LASTPROP $XRERR UNIQUE?
J 0
(-6250 1425);
DISPLAY 0.638298 (-6250 1425);
PAINT MONO (-6250 1425);
DISPLAY INVISIBLE (-6250 1425);
WIRE 16 -1 (-7700 3750)(-8825 3750);
FORCEPROP 2 LAST SIG_NAME RT_CPU1_P1_SCAN_MODE
J 0
(-8435 3760);
DISPLAY 0.680851 (-8435 3760);
PAINT SKYBLUE (-8435 3760);
WIRE 16 -1 (-8825 3875)(-8825 3750);
WIRE 16 -1 (-8825 3750)(-8825 3400);
WIRE 16 -1 (-1475 1200)(-1475 900);
WIRE 16 -1 (-2575 900)(-1475 900);
FORCEPROP 2 LAST SIG_NAME JTAG_TDI_RT_CPU1_P1
J 0
(-2410 910);
DISPLAY 0.680851 (-2410 910);
PAINT WHITE (-2410 910);
WIRE 16 -1 (-1200 1200)(-1200 950);
WIRE 16 -1 (-2575 950)(-1200 950);
FORCEPROP 2 LAST SIG_NAME JTAG_TMS_RT_CPU1_P1
J 0
(-2385 960);
DISPLAY 0.680851 (-2385 960);
PAINT WHITE (-2385 960);
WIRE 16 -1 (-925 1200)(-925 1000);
WIRE 16 -1 (-2575 1000)(-925 1000);
FORCEPROP 2 LAST SIG_NAME JTAG_TDO_RT_CPU1_P1
J 0
(-2385 1010);
DISPLAY 0.680851 (-2385 1010);
PAINT WHITE (-2385 1010);
WIRE 16 -1 (-650 1225)(-650 1050);
WIRE 16 -1 (-650 1050)(-650 775);
WIRE 16 -1 (-2575 1050)(-650 1050);
FORCEPROP 2 LAST SIG_NAME JTAG_TCK_RT_CPU1_P1
J 0
(-2410 1060);
DISPLAY 0.680851 (-2410 1060);
PAINT WHITE (-2410 1060);
WIRE 16 -1 (-1475 1400)(-1475 1550);
WIRE 16 -1 (-1475 1550)(-1200 1550);
WIRE 16 -1 (-1200 1550)(-925 1550);
WIRE 16 -1 (-1200 1400)(-1200 1550);
WIRE 16 -1 (-925 1550)(-650 1550);
WIRE 16 -1 (-925 1400)(-925 1550);
WIRE 16 -1 (-650 1425)(-650 1550);
WIRE 16 -1 (-650 1550)(-650 1575);
WIRE 16 -1 (-3625 3300)(-2625 3300);
FORCEPROP 2 LAST SIG_NAME JTAG_TMS_RT_CPU1_P1
J 0
(-3435 3310);
DISPLAY 0.680851 (-3435 3310);
PAINT WHITE (-3435 3310);
WIRE 16 -1 (-1325 5175)(-1325 5450);
WIRE 16 -1 (-400 5450)(-1325 5450);
FORCEPROP 2 LAST SIG_NAME RST_RT_CPU1_P1_RESET_R_N
J 0
(-1285 5485);
DISPLAY 0.680851 (-1285 5485);
PAINT SKYBLUE (-1285 5485);
WIRE 16 -1 (-1325 5800)(-1325 5450);
WIRE 16 -1 (-1975 5625)(-3475 5625);
FORCEPROP 2 LAST SIG_NAME RT_CPU1_P1_ADDR3
J 0
(-2760 5660);
DISPLAY 0.680851 (-2760 5660);
PAINT SKYBLUE (-2760 5660);
WIRE 16 -1 (-3475 5850)(-3475 5625);
WIRE 16 -1 (-3475 5625)(-3475 5275);
WIRE 16 -1 (-3175 5275)(-3175 5525);
WIRE 16 -1 (-1975 5525)(-3175 5525);
FORCEPROP 2 LAST SIG_NAME RT_CPU1_P1_ADDR2
J 0
(-2760 5535);
DISPLAY 0.680851 (-2760 5535);
PAINT SKYBLUE (-2760 5535);
WIRE 16 -1 (-3175 5525)(-3175 5850);
WIRE 16 -1 (-2825 5275)(-2825 5425);
WIRE 16 -1 (-1975 5425)(-2825 5425);
FORCEPROP 2 LAST SIG_NAME RT_CPU1_P1_ADDR1
J 0
(-2760 5435);
DISPLAY 0.680851 (-2760 5435);
PAINT SKYBLUE (-2760 5435);
WIRE 16 -1 (-2825 5425)(-2825 5825);
WIRE 16 -1 (-4875 2300)(-5775 2300);
FORCEPROP 2 LAST SIG_NAME RT_CPU1_P1_ADDR3
J 0
(-5635 2310);
DISPLAY 0.680851 (-5635 2310);
PAINT SKYBLUE (-5635 2310);
WIRE 16 -1 (-4875 1800)(-5950 1800);
FORCEPROP 2 LAST SIG_NAME TEST2_RT_CPU1_P1
J 0
(-5635 1810);
DISPLAY 0.680851 (-5635 1810);
PAINT SKYBLUE (-5635 1810);
WIRE 16 -1 (-4875 1900)(-5950 1900);
FORCEPROP 2 LAST SIG_NAME TEST1_RT_CPU1_P1
J 0
(-5635 1910);
DISPLAY 0.680851 (-5635 1910);
PAINT SKYBLUE (-5635 1910);
WIRE 16 -1 (-4875 2000)(-5950 2000);
FORCEPROP 2 LAST SIG_NAME TEST0_RT_CPU1_P1
J 0
(-5635 2010);
DISPLAY 0.680851 (-5635 2010);
PAINT SKYBLUE (-5635 2010);
WIRE 16 -1 (-4875 2650)(-6100 2650);
FORCEPROP 2 LAST SIG_NAME SMB_RT_CPU1_P1_R2_SDA
J 0
(-5860 2660);
DISPLAY 0.680851 (-5860 2660);
PAINT SKYBLUE (-5860 2660);
FORCEPROP 2 LASTPROP $XRERR UNIQUE?
J 0
(-6100 2660);
DISPLAY 0.638298 (-6100 2660);
PAINT MONO (-6100 2660);
DISPLAY INVISIBLE (-6100 2660);
WIRE 16 -1 (-1150 5300)(-425 5300);
WIRE 16 -1 (-1150 5175)(-1150 5300);
FORCEPROP 2 LAST SIG_NAME RST_RT_CPU1_P1_PERST_R_N
J 0
(-1185 5335);
DISPLAY 0.680851 (-1185 5335);
PAINT SKYBLUE (-1185 5335);
WIRE 16 -1 (-4875 5500)(-4875 5650);
WIRE 16 -1 (-4050 5650)(-4875 5650);
FORCEPROP 2 LAST SIG_NAME MODE_RT_CPU1_P1
J 0
(-4660 5660);
DISPLAY 0.680851 (-4660 5660);
PAINT SKYBLUE (-4660 5660);
WIRE 16 -1 (-4875 5825)(-4875 5650);
WIRE 16 -1 (-6275 5250)(-7275 5250);
FORCEPROP 2 LAST SIG_NAME JTAG_TEST_MODE_RT_CPU1_P1
J 0
(-7085 5260);
DISPLAY 0.680851 (-7085 5260);
PAINT SKYBLUE (-7085 5260);
WIRE 16 -1 (-7275 5750)(-7275 5250);
WIRE 16 -1 (-7275 5250)(-7275 4950);
WIRE 16 -1 (-7575 4975)(-7575 5325);
WIRE 16 -1 (-6275 5325)(-7575 5325);
FORCEPROP 2 LAST SIG_NAME TEST2_RT_CPU1_P1
J 0
(-6835 5335);
DISPLAY 0.680851 (-6835 5335);
PAINT SKYBLUE (-6835 5335);
WIRE 16 -1 (-7575 5725)(-7575 5325);
WIRE 16 -1 (-8800 5000)(-8800 5550);
WIRE 16 -1 (-6275 5550)(-8800 5550);
FORCEPROP 2 LAST SIG_NAME GPIO2_RT_CPU1_P1
J 0
(-6835 5560);
DISPLAY 0.680851 (-6835 5560);
PAINT SKYBLUE (-6835 5560);
WIRE 16 -1 (-8800 5750)(-8800 5550);
WIRE 16 -1 (-6275 5475)(-8500 5475);
FORCEPROP 2 LAST SIG_NAME GPIO3_RT_CPU1_P1
J 0
(-6860 5485);
DISPLAY 0.680851 (-6860 5485);
PAINT SKYBLUE (-6860 5485);
WIRE 16 -1 (-8500 5475)(-8500 5000);
WIRE 16 -1 (-8175 5000)(-8175 5425);
WIRE 16 -1 (-6275 5425)(-8175 5425);
FORCEPROP 2 LAST SIG_NAME TEST0_RT_CPU1_P1
J 0
(-6835 5435);
DISPLAY 0.680851 (-6835 5435);
PAINT SKYBLUE (-6835 5435);
WIRE 16 -1 (-8175 5750)(-8175 5425);
WIRE 16 -1 (-4875 3100)(-5825 3100);
FORCEPROP 2 LAST SIG_NAME GPIO3_RT_CPU1_P1
J 0
(-5685 3110);
DISPLAY 0.680851 (-5685 3110);
PAINT SKYBLUE (-5685 3110);
WIRE 16 -1 (-7875 4975)(-7875 5375);
WIRE 16 -1 (-6275 5375)(-7875 5375);
FORCEPROP 2 LAST SIG_NAME TEST1_RT_CPU1_P1
J 0
(-6835 5385);
DISPLAY 0.680851 (-6835 5385);
PAINT SKYBLUE (-6835 5385);
WIRE 16 -1 (-7875 5700)(-7875 5375);
WIRE 16 -1 (-4875 900)(-6150 900);
FORCEPROP 0 LAST SIG_NAME CLK_100M_RETIMER_CPU1_P1_DN
J 0
(-5910 910);
DISPLAY 0.680851 (-5910 910);
PAINT SKYBLUE (-5910 910);
FORCEPROP 2 LASTPROP $XRERR UNIQUE?
J 0
(-6150 910);
DISPLAY 0.638298 (-6150 910);
PAINT MONO (-6150 910);
DISPLAY INVISIBLE (-6150 910);
WIRE 16 -1 (-6150 900)(-6350 900);
WIRE 16 -1 (-6150 900)(-6150 675);
WIRE 16 -1 (-6550 900)(-7850 900);
FORCEPROP 2 LAST SIG_NAME CLK_100M_RETIMER_CPU1_P1_R_DN
J 0
(-7810 910);
DISPLAY 0.680851 (-7810 910);
PAINT SKYBLUE (-7810 910);
WIRE 16 -1 (-6550 1050)(-7850 1050);
FORCEPROP 2 LAST SIG_NAME CLK_100M_RETIMER_CPU1_P1_R_DP
J 0
(-7785 1060);
DISPLAY 0.680851 (-7785 1060);
PAINT SKYBLUE (-7785 1060);
WIRE 16 -1 (-4875 1050)(-6000 1050);
FORCEPROP 2 LAST SIG_NAME CLK_100M_RETIMER_CPU1_P1_DP
J 0
(-5910 1060);
DISPLAY 0.680851 (-5910 1060);
PAINT SKYBLUE (-5910 1060);
FORCEPROP 2 LASTPROP $XRERR UNIQUE?
J 0
(-6150 1060);
DISPLAY 0.638298 (-6150 1060);
PAINT MONO (-6150 1060);
DISPLAY INVISIBLE (-6150 1060);
WIRE 16 -1 (-6000 1050)(-6000 675);
WIRE 16 -1 (-6000 1050)(-6350 1050);
WIRE 16 -1 (-4875 2400)(-5775 2400);
FORCEPROP 2 LAST SIG_NAME RT_CPU1_P1_ADDR2
J 0
(-5635 2410);
DISPLAY 0.680851 (-5635 2410);
PAINT SKYBLUE (-5635 2410);
WIRE 16 -1 (-4875 2500)(-5775 2500);
FORCEPROP 2 LAST SIG_NAME RT_CPU1_P1_ADDR1
J 0
(-5635 2510);
DISPLAY 0.680851 (-5635 2510);
PAINT SKYBLUE (-5635 2510);
WIRE 16 -1 (-6300 2650)(-7450 2650);
FORCEPROP 2 LAST SIG_NAME SMB_RT_CPU1_P1_R_SDA
J 0
(-7285 2660);
DISPLAY 0.680851 (-7285 2660);
PAINT SKYBLUE (-7285 2660);
WIRE 16 -1 (-6300 2750)(-7450 2750);
FORCEPROP 2 LAST SIG_NAME SMB_RT_CPU1_P1_R_SCL
J 0
(-7285 2760);
DISPLAY 0.680851 (-7285 2760);
PAINT SKYBLUE (-7285 2760);
WIRE 16 -1 (-4875 3200)(-5825 3200);
FORCEPROP 2 LAST SIG_NAME GPIO2_RT_CPU1_P1
J 0
(-5685 3210);
DISPLAY 0.680851 (-5685 3210);
PAINT SKYBLUE (-5685 3210);
WIRE 16 -1 (-1450 3275)(-1450 3425);
WIRE 16 -1 (-650 3425)(-1450 3425);
FORCEPROP 2 LAST SIG_NAME RXDET_BYP_RT_CPU1_P1
J 0
(-1335 3435);
DISPLAY 0.680851 (-1335 3435);
PAINT WHITE (-1335 3435);
WIRE 16 -1 (-1450 3425)(-1450 3600);
WIRE 16 -1 (-4875 2750)(-6100 2750);
FORCEPROP 2 LAST SIG_NAME SMB_RT_CPU1_P1_R2_SCL
J 0
(-5860 2760);
DISPLAY 0.680851 (-5860 2760);
PAINT SKYBLUE (-5860 2760);
FORCEPROP 2 LASTPROP $XRERR UNIQUE?
J 0
(-6100 2760);
DISPLAY 0.638298 (-6100 2760);
PAINT MONO (-6100 2760);
DISPLAY INVISIBLE (-6100 2760);
WIRE 16 -1 (-2825 5075)(-2825 4900);
WIRE 16 -1 (-2825 4900)(-3175 4900);
WIRE 16 -1 (-3175 5075)(-3175 4900);
WIRE 16 -1 (-3175 4900)(-3475 4900);
WIRE 16 -1 (-3475 5075)(-3475 4900);
WIRE 16 -1 (-3475 4900)(-3475 4800);
WIRE 16 -1 (-3175 6275)(-2825 6275);
WIRE 16 -1 (-3475 6275)(-3175 6275);
WIRE 16 -1 (-3175 6275)(-3175 6050);
WIRE 16 -1 (-2825 6275)(-2825 6025);
WIRE 16 -1 (-3475 6050)(-3475 6275);
WIRE 16 -1 (-3475 6275)(-3475 6325);
WIRE 16 -1 (-7575 6150)(-7275 6150);
WIRE 16 -1 (-7575 6150)(-7875 6150);
WIRE 16 -1 (-7575 6150)(-7575 5925);
WIRE 16 -1 (-7275 6150)(-7275 5950);
WIRE 16 -1 (-7875 6150)(-8175 6150);
WIRE 16 -1 (-7875 6150)(-7875 5900);
WIRE 16 -1 (-8175 6150)(-8175 5950);
WIRE 16 -1 (-8800 6150)(-8175 6150);
WIRE 16 -1 (-8800 6200)(-8800 6150);
WIRE 16 -1 (-8800 6150)(-8800 5950);
WIRE 16 -1 (-8800 4800)(-8800 4575);
WIRE 16 -1 (-8800 4575)(-8500 4575);
WIRE 16 -1 (-8500 4575)(-8175 4575);
WIRE 16 -1 (-8500 4800)(-8500 4575);
WIRE 16 -1 (-8175 4800)(-8175 4575);
WIRE 16 -1 (-7875 4575)(-8175 4575);
WIRE 16 -1 (-7575 4575)(-7875 4575);
WIRE 16 -1 (-7875 4775)(-7875 4575);
WIRE 16 -1 (-7575 4775)(-7575 4575);
WIRE 16 -1 (-7575 4575)(-7275 4575);
WIRE 16 -1 (-7275 4750)(-7275 4575);
WIRE 16 -1 (-7275 4575)(-7275 4450);
WIRE 16 -1 (-2325 2050)(-950 2050);
FORCEPROP 2 LAST SIG_NAME RST_RT_CPU1_P1_PERST_R_N
J 0
(-1785 2060);
DISPLAY 0.680851 (-1785 2060);
PAINT SKYBLUE (-1785 2060);
WIRE 16 -1 (-3625 3500)(-2625 3500);
FORCEPROP 2 LAST SIG_NAME JTAG_TCK_RT_CPU1_P1
J 0
(-3460 3510);
DISPLAY 0.680851 (-3460 3510);
PAINT WHITE (-3460 3510);
WIRE 16 -1 (-3625 3400)(-2625 3400);
FORCEPROP 2 LAST SIG_NAME JTAG_TDO_RT_CPU1_P1
J 0
(-3435 3410);
DISPLAY 0.680851 (-3435 3410);
PAINT WHITE (-3435 3410);
WIRE 16 -1 (-3625 1950)(-2525 1950);
FORCEPROP 2 LAST SIG_NAME RST_RT_CPU1_P1_RESET_N
J 0
(-3435 1960);
DISPLAY 0.680851 (-3435 1960);
PAINT SKYBLUE (-3435 1960);
FORCEPROP 2 LASTPROP $XRERR UNIQUE?
J 0
(-3675 1960);
DISPLAY 0.638298 (-3675 1960);
PAINT MONO (-3675 1960);
DISPLAY INVISIBLE (-3675 1960);
WIRE 16 -1 (-3625 3200)(-2650 3200);
FORCEPROP 2 LAST SIG_NAME JTAG_TDI_RT_CPU1_P1
J 0
(-3460 3210);
DISPLAY 0.680851 (-3460 3210);
PAINT WHITE (-3460 3210);
WIRE 16 -1 (-3625 3100)(-2650 3100);
FORCEPROP 2 LAST SIG_NAME JTAG_TRST_RT_CPU1_P1_N
J 0
(-3460 3110);
DISPLAY 0.680851 (-3460 3110);
PAINT WHITE (-3460 3110);
FORCEPROP 2 LASTPROP $XRERR UNIQUE?
J 0
(-3700 3110);
DISPLAY 0.638298 (-3700 3110);
PAINT MONO (-3700 3110);
DISPLAY INVISIBLE (-3700 3110);
WIRE 16 -1 (-3625 2950)(-2375 2950);
FORCEPROP 2 LAST SIG_NAME JTAG_TEST_MODE_RT_CPU1_P1
J 0
(-3435 2960);
DISPLAY 0.680851 (-3435 2960);
PAINT SKYBLUE (-3435 2960);
WIRE 16 -1 (-3625 2650)(-2300 2650);
FORCEPROP 2 LAST SIG_NAME MODE_RT_CPU1_P1
J 0
(-3310 2660);
DISPLAY 0.680851 (-3310 2660);
PAINT SKYBLUE (-3310 2660);
WIRE 16 -1 (-3625 2550)(-2300 2550);
FORCEPROP 2 LAST SIG_NAME RXDET_BYP_RT_CPU1_P1
J 0
(-3310 2560);
DISPLAY 0.680851 (-3310 2560);
PAINT WHITE (-3310 2560);
WIRE 16 -1 (-3625 2450)(-2275 2450);
FORCEPROP 2 LAST SIG_NAME RT_CPU1_P1_SCAN_MODE
J 0
(-3335 2460);
DISPLAY 0.680851 (-3335 2460);
PAINT SKYBLUE (-3335 2460);
WIRE 16 -1 (-2325 1950)(-950 1950);
FORCEPROP 2 LAST SIG_NAME RST_RT_CPU1_P1_RESET_R_N
J 0
(-1810 1960);
DISPLAY 0.680851 (-1810 1960);
PAINT SKYBLUE (-1810 1960);
WIRE 16 -1 (-3625 2050)(-2525 2050);
FORCEPROP 2 LAST SIG_NAME RST_RT_CPU1_P1_PERST_N
J 0
(-3460 2060);
DISPLAY 0.680851 (-3460 2060);
PAINT SKYBLUE (-3460 2060);
FORCEPROP 2 LASTPROP $XRERR UNIQUE?
J 0
(-3700 2060);
DISPLAY 0.638298 (-3700 2060);
PAINT MONO (-3700 2060);
DISPLAY INVISIBLE (-3700 2060);
WIRE 16 -1 (-3625 2150)(-2625 2150);
FORCEPROP 2 LAST SIG_NAME CLKREQ_RT_CPU1_P1_N
J 0
(-3360 2160);
DISPLAY 0.680851 (-3360 2160);
PAINT WHITE (-3360 2160);
FORCEPROP 2 LASTPROP $XRERR UNIQUE?
J 0
(-3600 2160);
DISPLAY 0.638298 (-3600 2160);
PAINT MONO (-3600 2160);
DISPLAY INVISIBLE (-3600 2160);
DOT 1 (-8825 3750);
DOT 1 (-1450 3425);
DOT 1 (-6000 1050);
DOT 1 (-3475 4900);
DOT 1 (-3475 5625);
DOT 1 (-3175 4900);
DOT 1 (-3175 5525);
DOT 1 (-2825 5425);
DOT 1 (-3475 6275);
DOT 1 (-3175 6275);
DOT 1 (-7875 4575);
DOT 1 (-6150 900);
DOT 1 (-1325 5450);
DOT 1 (-4875 5650);
DOT 1 (-7575 6150);
DOT 1 (-7575 5325);
DOT 1 (-7275 4575);
DOT 1 (-7575 4575);
DOT 1 (-7875 6150);
DOT 1 (-8175 6150);
DOT 1 (-8800 6150);
DOT 1 (-8175 5425);
DOT 1 (-8175 4575);
DOT 1 (-8500 4575);
DOT 1 (-8800 5550);
DOT 1 (-7875 5375);
DOT 1 (-7275 5250);
DOT 1 (-1200 1550);
DOT 1 (-650 1050);
DOT 1 (-925 1550);
DOT 1 (-650 1550);
FORCENOTE
CPU1 P1 RT ADDR: 0X48 (8-BIT) / 0X24 (7-BIT)
(-4125 4475) 0;
DISPLAY LEFT (-4125 4475);
DISPLAY 1.595745 (-4125 4475);
QUIT
